FILE_TYPE = MACRO_DRAWING;
SET COLOR_WIRE YELLOW;
SET COLOR_PROP ORANGE;
SET COLOR_DOT WHITE;
SET COLOR_ARC YELLOW;
SET COLOR_BODY GREEN;
SET COLOR_NOTE PURPLE;
SET PROP_DISPLAY VALUE;
SET PAGE_NUMBER P75;
FORCEADD OFFPAGE..2
(-7225 4250);
FORCEPROP 2 LAST $XR2 164 
J 0
(-6856 4250);
DISPLAY 0.638298 (-6856 4250);
PAINT MONO (-6856 4250);
FORCEPROP 2 LAST $XR1 76 
J 0
(-6946 4250);
DISPLAY 0.638298 (-6946 4250);
PAINT MONO (-6946 4250);
FORCEPROP 2 LAST $XR0 27 
J 0
(-7036 4250);
DISPLAY 0.638298 (-7036 4250);
PAINT MONO (-7036 4250);
FORCEPROP 2 LAST CDS_LIB standard
J 0
(-7225 4250);
DISPLAY INVISIBLE (-7225 4250);
FORCEPROP 1 LAST OFFPAGE TRUE
J 0
(-6900 4125);
DISPLAY 0.872340 (-6900 4125);
PAINT GREEN (-6900 4125);
DISPLAY INVISIBLE (-6900 4125);
FORCEPROP 1 LAST COMMENT_BODY TRUE
J 0
(-7270 4155);
DISPLAY 0.872340 (-7270 4155);
PAINT GREEN (-7270 4155);
DISPLAY INVISIBLE (-7270 4155);
FORCEPROP 2 LAST PATH I1
J 0
(-6925 4300);
DISPLAY 1.021277 (-6925 4300);
DISPLAY INVISIBLE (-6925 4300);
FORCEADD Q_RES..1
(-8650 3600);
FORCEPROP 1 LAST LOCATION R751
J 0
(-8875 3600);
DISPLAY 0.489362 (-8875 3600);
PAINT SKYBLUE (-8875 3600);
FORCEPROP 2 LAST $SEC 1
J 0
(-8700 3800);
DISPLAY 0.680851 (-8700 3800);
PAINT MONO (-8700 3800);
DISPLAY INVISIBLE (-8700 3800);
FORCEPROP 2 LAST CDS_SEC 1
J 0
(-8700 3800);
DISPLAY 1.021277 (-8700 3800);
DISPLAY INVISIBLE (-8700 3800);
FORCEPROP 1 LASTPIN (-8750 3600) $PN 1
J 0
(-8738 3612);
DISPLAY 0.489362 (-8738 3612);
FORCEPROP 1 LASTPIN (-8550 3600) $PN 2
J 0
(-8588 3612);
DISPLAY 0.489362 (-8588 3612);
FORCEPROP 1 LAST VALUE 10K
J 2
(-8450 3600);
DISPLAY 0.489362 (-8450 3600);
PAINT SKYBLUE (-8450 3600);
FORCEPROP 1 LAST TOLERANCE 5%
J 0
(-8425 3600);
DISPLAY 0.489362 (-8425 3600);
PAINT SKYBLUE (-8425 3600);
FORCEPROP 1 LAST MATERIAL CHIP
J 0
(-8325 3600);
DISPLAY 0.489362 (-8325 3600);
PAINT SKYBLUE (-8325 3600);
FORCEPROP 1 LAST PACK_TYPE 0402LF
J 0
(-8750 3675);
DISPLAY 0.510638 (-8750 3675);
PAINT SKYBLUE (-8750 3675);
DISPLAY INVISIBLE (-8750 3675);
FORCEPROP 1 LAST WATTAGE 1/16W
J 2
(-8475 3675);
DISPLAY 0.510638 (-8475 3675);
PAINT SKYBLUE (-8475 3675);
DISPLAY INVISIBLE (-8475 3675);
FORCEPROP 2 LAST CDS_LIB pure_quanta
J 0
(-8650 3600);
PAINT MONO (-8650 3600);
DISPLAY INVISIBLE (-8650 3600);
FORCEPROP 1 LAST PATH I12
J 0
(-8700 3750);
DISPLAY 0.978723 (-8700 3750);
PAINT WHITE (-8700 3750);
DISPLAY INVISIBLE (-8700 3750);
FORCEPROP 1 LAST PART_NUMBER CS31002JB08
J 0
(-8750 3650);
DISPLAY 0.510638 (-8750 3650);
PAINT SKYBLUE (-8750 3650);
DISPLAY INVISIBLE (-8750 3650);
FORCEADD UNIVERSAL_GND..1
(-8950 2850);
FORCEPROP 3 LASTPIN (-8950 2900) SIG_NAME GND\g
J 0
(-8940 2910);
DISPLAY 0.659574 (-8940 2910);
PAINT MONO (-8940 2910);
DISPLAY INVISIBLE (-8940 2910);
FORCEPROP 2 LAST CDS_LIB pure_quanta_power
J 0
(-8950 2850);
DISPLAY INVISIBLE (-8950 2850);
FORCEPROP 1 LAST HDL_POWER GND
J 1
(-8925 2775);
DISPLAY 0.872340 (-8925 2775);
PAINT GREEN (-8925 2775);
DISPLAY INVISIBLE (-8925 2775);
FORCEPROP 1 LAST PATH I15
J 0
(-8875 2850);
DISPLAY 0.872340 (-8875 2850);
PAINT AQUA (-8875 2850);
DISPLAY INVISIBLE (-8875 2850);
FORCEADD OFFPAGE..2
(-7225 5450);
FORCEPROP 2 LAST $XR2 164 
J 0
(-6856 5450);
DISPLAY 0.638298 (-6856 5450);
PAINT MONO (-6856 5450);
FORCEPROP 2 LAST $XR1 76 
J 0
(-6946 5450);
DISPLAY 0.638298 (-6946 5450);
PAINT MONO (-6946 5450);
FORCEPROP 2 LAST $XR0 27 
J 0
(-7036 5450);
DISPLAY 0.638298 (-7036 5450);
PAINT MONO (-7036 5450);
FORCEPROP 2 LAST CDS_LIB standard
J 0
(-7225 5450);
DISPLAY INVISIBLE (-7225 5450);
FORCEPROP 1 LAST OFFPAGE TRUE
J 0
(-6900 5325);
DISPLAY 0.872340 (-6900 5325);
PAINT GREEN (-6900 5325);
DISPLAY INVISIBLE (-6900 5325);
FORCEPROP 1 LAST COMMENT_BODY TRUE
J 0
(-7270 5355);
DISPLAY 0.872340 (-7270 5355);
PAINT GREEN (-7270 5355);
DISPLAY INVISIBLE (-7270 5355);
FORCEPROP 2 LAST PATH I27
J 0
(-6850 5500);
DISPLAY 1.021277 (-6850 5500);
DISPLAY INVISIBLE (-6850 5500);
FORCEADD OFFPAGE..2
(-7225 5175);
FORCEPROP 2 LAST $XR1 28 
J 0
(-6946 5175);
DISPLAY 0.638298 (-6946 5175);
PAINT MONO (-6946 5175);
FORCEPROP 2 LAST $XR0 76 
J 0
(-7036 5175);
DISPLAY 0.638298 (-7036 5175);
PAINT MONO (-7036 5175);
FORCEPROP 2 LAST CDS_LIB standard
J 0
(-7225 5175);
DISPLAY INVISIBLE (-7225 5175);
FORCEPROP 1 LAST OFFPAGE TRUE
J 0
(-6900 5050);
DISPLAY 0.872340 (-6900 5050);
PAINT GREEN (-6900 5050);
DISPLAY INVISIBLE (-6900 5050);
FORCEPROP 1 LAST COMMENT_BODY TRUE
J 0
(-7270 5080);
DISPLAY 0.872340 (-7270 5080);
PAINT GREEN (-7270 5080);
DISPLAY INVISIBLE (-7270 5080);
FORCEPROP 2 LAST PATH I28
J 0
(-6925 5225);
DISPLAY 1.021277 (-6925 5225);
DISPLAY INVISIBLE (-6925 5225);
FORCEADD OFFPAGE..2
(-7225 3975);
FORCEPROP 2 LAST $XR1 28 
J 0
(-6946 3975);
DISPLAY 0.638298 (-6946 3975);
PAINT MONO (-6946 3975);
FORCEPROP 2 LAST $XR0 76 
J 0
(-7036 3975);
DISPLAY 0.638298 (-7036 3975);
PAINT MONO (-7036 3975);
FORCEPROP 2 LAST CDS_LIB standard
J 0
(-7225 3975);
DISPLAY INVISIBLE (-7225 3975);
FORCEPROP 1 LAST OFFPAGE TRUE
J 0
(-6900 3850);
DISPLAY 0.872340 (-6900 3850);
PAINT GREEN (-6900 3850);
DISPLAY INVISIBLE (-6900 3850);
FORCEPROP 1 LAST COMMENT_BODY TRUE
J 0
(-7270 3880);
DISPLAY 0.872340 (-7270 3880);
PAINT GREEN (-7270 3880);
DISPLAY INVISIBLE (-7270 3880);
FORCEPROP 2 LAST PATH I3
J 0
(-6925 4025);
DISPLAY 1.021277 (-6925 4025);
DISPLAY INVISIBLE (-6925 4025);
FORCEADD OFFPAGE..2
(-7225 4550);
FORCEPROP 2 LAST $XR1 29 
J 0
(-6946 4550);
DISPLAY 0.638298 (-6946 4550);
PAINT MONO (-6946 4550);
FORCEPROP 2 LAST $XR0 76 
J 0
(-7036 4550);
DISPLAY 0.638298 (-7036 4550);
PAINT MONO (-7036 4550);
FORCEPROP 2 LAST CDS_LIB standard
J 0
(-7225 4550);
DISPLAY INVISIBLE (-7225 4550);
FORCEPROP 1 LAST OFFPAGE TRUE
J 0
(-6900 4425);
DISPLAY 0.872340 (-6900 4425);
PAINT GREEN (-6900 4425);
DISPLAY INVISIBLE (-6900 4425);
FORCEPROP 1 LAST COMMENT_BODY TRUE
J 0
(-7270 4455);
DISPLAY 0.872340 (-7270 4455);
PAINT GREEN (-7270 4455);
DISPLAY INVISIBLE (-7270 4455);
FORCEPROP 2 LAST PATH I32
J 0
(-6925 4600);
DISPLAY 1.021277 (-6925 4600);
DISPLAY INVISIBLE (-6925 4600);
FORCEADD OFFPAGE..2
(-7225 4800);
FORCEPROP 2 LAST $XR2 55 
J 0
(-6856 4800);
DISPLAY 0.638298 (-6856 4800);
PAINT MONO (-6856 4800);
FORCEPROP 2 LAST $XR1 76 
J 0
(-6946 4800);
DISPLAY 0.638298 (-6946 4800);
PAINT MONO (-6946 4800);
FORCEPROP 2 LAST $XR0 28 
J 0
(-7036 4800);
DISPLAY 0.638298 (-7036 4800);
PAINT MONO (-7036 4800);
FORCEPROP 2 LAST CDS_LIB standard
J 0
(-7225 4800);
DISPLAY INVISIBLE (-7225 4800);
FORCEPROP 1 LAST OFFPAGE TRUE
J 0
(-6900 4675);
DISPLAY 0.872340 (-6900 4675);
PAINT GREEN (-6900 4675);
DISPLAY INVISIBLE (-6900 4675);
FORCEPROP 1 LAST COMMENT_BODY TRUE
J 0
(-7270 4705);
DISPLAY 0.872340 (-7270 4705);
PAINT GREEN (-7270 4705);
DISPLAY INVISIBLE (-7270 4705);
FORCEPROP 2 LAST PATH I33
J 0
(-6850 4850);
DISPLAY 1.021277 (-6850 4850);
DISPLAY INVISIBLE (-6850 4850);
FORCEADD OFFPAGE..2
(-7225 4925);
FORCEPROP 2 LAST $XR3 150 
J 0
(-6766 4925);
DISPLAY 0.638298 (-6766 4925);
PAINT MONO (-6766 4925);
FORCEPROP 2 LAST $XR2 81 
J 0
(-6856 4925);
DISPLAY 0.638298 (-6856 4925);
PAINT MONO (-6856 4925);
FORCEPROP 2 LAST $XR1 76 
J 0
(-6946 4925);
DISPLAY 0.638298 (-6946 4925);
PAINT MONO (-6946 4925);
FORCEPROP 2 LAST $XR0 29 
J 0
(-7036 4925);
DISPLAY 0.638298 (-7036 4925);
PAINT MONO (-7036 4925);
FORCEPROP 2 LAST CDS_LIB standard
J 0
(-7225 4925);
DISPLAY INVISIBLE (-7225 4925);
FORCEPROP 1 LAST OFFPAGE TRUE
J 0
(-6900 4800);
DISPLAY 0.872340 (-6900 4800);
PAINT GREEN (-6900 4800);
DISPLAY INVISIBLE (-6900 4800);
FORCEPROP 1 LAST COMMENT_BODY TRUE
J 0
(-7270 4830);
DISPLAY 0.872340 (-7270 4830);
PAINT GREEN (-7270 4830);
DISPLAY INVISIBLE (-7270 4830);
FORCEPROP 2 LAST PATH I35
J 0
(-6850 4975);
DISPLAY 1.021277 (-6850 4975);
DISPLAY INVISIBLE (-6850 4975);
FORCEADD UNIVERSAL_POWER..1
(-8950 5950);
FORCEPROP 3 LASTPIN (-8950 5900) SIG_NAME PVDD18_S5_P0\g
J 0
(-8940 5910);
DISPLAY 0.659574 (-8940 5910);
PAINT MONO (-8940 5910);
DISPLAY INVISIBLE (-8940 5910);
FORCEPROP 1 LAST HDL_POWER PVDD18_S5_P0
J 1
(-8950 6000);
DISPLAY 0.489362 (-8950 6000);
PAINT GREEN (-8950 6000);
FORCEPROP 2 LAST CDS_LIB pure_quanta_power
J 0
(-8950 5950);
DISPLAY INVISIBLE (-8950 5950);
FORCEPROP 1 LAST PATH I39
J 0
(-8900 5975);
DISPLAY 0.872340 (-8900 5975);
PAINT AQUA (-8900 5975);
DISPLAY INVISIBLE (-8900 5975);
FORCEADD OFFPAGE..2
(-7225 3600);
FORCEPROP 2 LAST $XR2 55 
J 0
(-6856 3600);
DISPLAY 0.638298 (-6856 3600);
PAINT MONO (-6856 3600);
FORCEPROP 2 LAST $XR1 76 
J 0
(-6946 3600);
DISPLAY 0.638298 (-6946 3600);
PAINT MONO (-6946 3600);
FORCEPROP 2 LAST $XR0 28 
J 0
(-7036 3600);
DISPLAY 0.638298 (-7036 3600);
PAINT MONO (-7036 3600);
FORCEPROP 2 LAST CDS_LIB standard
J 0
(-7225 3600);
DISPLAY INVISIBLE (-7225 3600);
FORCEPROP 1 LAST OFFPAGE TRUE
J 0
(-6900 3475);
DISPLAY 0.872340 (-6900 3475);
PAINT GREEN (-6900 3475);
DISPLAY INVISIBLE (-6900 3475);
FORCEPROP 1 LAST COMMENT_BODY TRUE
J 0
(-7270 3505);
DISPLAY 0.872340 (-7270 3505);
PAINT GREEN (-7270 3505);
DISPLAY INVISIBLE (-7270 3505);
FORCEPROP 2 LAST PATH I4
J 0
(-6925 3650);
DISPLAY 1.021277 (-6925 3650);
DISPLAY INVISIBLE (-6925 3650);
FORCEADD Q_RES..1
(-8650 5450);
FORCEPROP 1 LAST LOCATION R729
J 0
(-8875 5450);
DISPLAY 0.489362 (-8875 5450);
PAINT SKYBLUE (-8875 5450);
FORCEPROP 2 LAST $SEC 1
J 0
(-8700 5650);
DISPLAY 0.680851 (-8700 5650);
PAINT MONO (-8700 5650);
DISPLAY INVISIBLE (-8700 5650);
FORCEPROP 2 LAST CDS_SEC 1
J 0
(-8700 5650);
DISPLAY 1.021277 (-8700 5650);
DISPLAY INVISIBLE (-8700 5650);
FORCEPROP 1 LASTPIN (-8750 5450) $PN 1
J 0
(-8738 5462);
DISPLAY 0.489362 (-8738 5462);
FORCEPROP 1 LASTPIN (-8550 5450) $PN 2
J 0
(-8588 5462);
DISPLAY 0.489362 (-8588 5462);
FORCEPROP 1 LAST VALUE 10K
J 2
(-8450 5450);
DISPLAY 0.489362 (-8450 5450);
PAINT SKYBLUE (-8450 5450);
FORCEPROP 1 LAST TOLERANCE 5%
J 0
(-8425 5450);
DISPLAY 0.489362 (-8425 5450);
PAINT SKYBLUE (-8425 5450);
FORCEPROP 1 LAST MATERIAL EMPTY
J 0
(-8325 5450);
DISPLAY 0.489362 (-8325 5450);
PAINT RED (-8325 5450);
FORCEPROP 1 LAST PACK_TYPE 0402LF
J 0
(-8750 5525);
DISPLAY 0.510638 (-8750 5525);
PAINT SKYBLUE (-8750 5525);
DISPLAY INVISIBLE (-8750 5525);
FORCEPROP 1 LAST WATTAGE 1/16W
J 2
(-8475 5525);
DISPLAY 0.510638 (-8475 5525);
PAINT SKYBLUE (-8475 5525);
DISPLAY INVISIBLE (-8475 5525);
FORCEPROP 2 LAST CDS_LIB pure_quanta
J 0
(-8650 5450);
PAINT MONO (-8650 5450);
DISPLAY INVISIBLE (-8650 5450);
FORCEPROP 1 LAST PATH I41
J 0
(-8700 5600);
DISPLAY 0.978723 (-8700 5600);
PAINT WHITE (-8700 5600);
DISPLAY INVISIBLE (-8700 5600);
FORCEPROP 1 LAST PART_NUMBER CS31002JB08
J 0
(-8750 5500);
DISPLAY 0.510638 (-8750 5500);
PAINT SKYBLUE (-8750 5500);
DISPLAY INVISIBLE (-8750 5500);
FORCEADD Q_RES..1
(-8625 5175);
FORCEPROP 1 LAST LOCATION R737
J 0
(-8875 5175);
DISPLAY 0.489362 (-8875 5175);
PAINT SKYBLUE (-8875 5175);
FORCEPROP 2 LAST $SEC 1
J 0
(-8675 5375);
DISPLAY 0.680851 (-8675 5375);
PAINT MONO (-8675 5375);
DISPLAY INVISIBLE (-8675 5375);
FORCEPROP 2 LAST CDS_SEC 1
J 0
(-8675 5375);
DISPLAY 1.021277 (-8675 5375);
DISPLAY INVISIBLE (-8675 5375);
FORCEPROP 1 LASTPIN (-8725 5175) $PN 1
J 0
(-8713 5187);
DISPLAY 0.489362 (-8713 5187);
FORCEPROP 1 LASTPIN (-8525 5175) $PN 2
J 0
(-8563 5187);
DISPLAY 0.489362 (-8563 5187);
FORCEPROP 1 LAST MATERIAL CHIP
J 0
(-8300 5175);
DISPLAY 0.489362 (-8300 5175);
PAINT SKYBLUE (-8300 5175);
FORCEPROP 1 LAST TOLERANCE 5%
J 0
(-8400 5175);
DISPLAY 0.489362 (-8400 5175);
PAINT SKYBLUE (-8400 5175);
FORCEPROP 1 LAST VALUE 10K
J 2
(-8425 5175);
DISPLAY 0.489362 (-8425 5175);
PAINT SKYBLUE (-8425 5175);
FORCEPROP 2 LAST CDS_LIB pure_quanta
J 0
(-8625 5175);
PAINT MONO (-8625 5175);
DISPLAY INVISIBLE (-8625 5175);
FORCEPROP 1 LAST WATTAGE 1/16W
J 2
(-8425 5250);
DISPLAY 0.510638 (-8425 5250);
PAINT SKYBLUE (-8425 5250);
DISPLAY INVISIBLE (-8425 5250);
FORCEPROP 1 LAST PACK_TYPE 0402LF
J 0
(-8725 5250);
DISPLAY 0.510638 (-8725 5250);
PAINT SKYBLUE (-8725 5250);
DISPLAY INVISIBLE (-8725 5250);
FORCEPROP 1 LAST PATH I43
J 0
(-8675 5325);
DISPLAY 0.978723 (-8675 5325);
PAINT WHITE (-8675 5325);
DISPLAY INVISIBLE (-8675 5325);
FORCEPROP 1 LAST PART_NUMBER CS31002JB08
J 0
(-8725 5225);
DISPLAY 0.510638 (-8725 5225);
PAINT SKYBLUE (-8725 5225);
DISPLAY INVISIBLE (-8725 5225);
FORCEADD Q_RES..1
(-8625 4800);
FORCEPROP 1 LAST LOCATION R740
J 0
(-8875 4800);
DISPLAY 0.489362 (-8875 4800);
PAINT SKYBLUE (-8875 4800);
FORCEPROP 2 LAST $SEC 1
J 0
(-8675 5000);
DISPLAY 0.680851 (-8675 5000);
PAINT MONO (-8675 5000);
DISPLAY INVISIBLE (-8675 5000);
FORCEPROP 2 LAST CDS_SEC 1
J 0
(-8675 5000);
DISPLAY 1.021277 (-8675 5000);
DISPLAY INVISIBLE (-8675 5000);
FORCEPROP 1 LASTPIN (-8725 4800) $PN 1
J 0
(-8713 4812);
DISPLAY 0.489362 (-8713 4812);
FORCEPROP 1 LASTPIN (-8525 4800) $PN 2
J 0
(-8563 4812);
DISPLAY 0.489362 (-8563 4812);
FORCEPROP 1 LAST VALUE 10K
J 2
(-8425 4800);
DISPLAY 0.489362 (-8425 4800);
PAINT SKYBLUE (-8425 4800);
FORCEPROP 1 LAST TOLERANCE 5%
J 0
(-8400 4800);
DISPLAY 0.489362 (-8400 4800);
PAINT SKYBLUE (-8400 4800);
FORCEPROP 1 LAST MATERIAL EMPTY
J 0
(-8300 4800);
DISPLAY 0.489362 (-8300 4800);
PAINT RED (-8300 4800);
FORCEPROP 1 LAST PACK_TYPE 0402LF
J 0
(-8725 4875);
DISPLAY 0.510638 (-8725 4875);
PAINT SKYBLUE (-8725 4875);
DISPLAY INVISIBLE (-8725 4875);
FORCEPROP 1 LAST WATTAGE 1/16W
J 2
(-8450 4875);
DISPLAY 0.510638 (-8450 4875);
PAINT SKYBLUE (-8450 4875);
DISPLAY INVISIBLE (-8450 4875);
FORCEPROP 2 LAST CDS_LIB pure_quanta
J 0
(-8625 4800);
PAINT MONO (-8625 4800);
DISPLAY INVISIBLE (-8625 4800);
FORCEPROP 1 LAST PATH I44
J 0
(-8675 4950);
DISPLAY 0.978723 (-8675 4950);
PAINT WHITE (-8675 4950);
DISPLAY INVISIBLE (-8675 4950);
FORCEPROP 1 LAST PART_NUMBER CS31002JB08
J 0
(-8725 4850);
DISPLAY 0.510638 (-8725 4850);
PAINT SKYBLUE (-8725 4850);
DISPLAY INVISIBLE (-8725 4850);
FORCEADD Q_RES..1
(-8625 4925);
FORCEPROP 1 LAST LOCATION R739
J 0
(-8875 4925);
DISPLAY 0.489362 (-8875 4925);
PAINT SKYBLUE (-8875 4925);
FORCEPROP 2 LAST $SEC 1
J 0
(-8675 5125);
DISPLAY 0.680851 (-8675 5125);
PAINT MONO (-8675 5125);
DISPLAY INVISIBLE (-8675 5125);
FORCEPROP 2 LAST CDS_SEC 1
J 0
(-8675 5125);
DISPLAY 1.021277 (-8675 5125);
DISPLAY INVISIBLE (-8675 5125);
FORCEPROP 1 LASTPIN (-8725 4925) $PN 1
J 0
(-8713 4937);
DISPLAY 0.489362 (-8713 4937);
FORCEPROP 1 LASTPIN (-8525 4925) $PN 2
J 0
(-8563 4937);
DISPLAY 0.489362 (-8563 4937);
FORCEPROP 1 LAST VALUE 10K
J 2
(-8425 4925);
DISPLAY 0.489362 (-8425 4925);
PAINT SKYBLUE (-8425 4925);
FORCEPROP 1 LAST TOLERANCE 5%
J 0
(-8400 4925);
DISPLAY 0.489362 (-8400 4925);
PAINT SKYBLUE (-8400 4925);
FORCEPROP 1 LAST MATERIAL EMPTY
J 0
(-8300 4925);
DISPLAY 0.489362 (-8300 4925);
PAINT RED (-8300 4925);
FORCEPROP 1 LAST PACK_TYPE 0402LF
J 0
(-8725 5000);
DISPLAY 0.510638 (-8725 5000);
PAINT SKYBLUE (-8725 5000);
DISPLAY INVISIBLE (-8725 5000);
FORCEPROP 1 LAST WATTAGE 1/16W
J 2
(-8450 5000);
DISPLAY 0.510638 (-8450 5000);
PAINT SKYBLUE (-8450 5000);
DISPLAY INVISIBLE (-8450 5000);
FORCEPROP 2 LAST CDS_LIB pure_quanta
J 0
(-8625 4925);
PAINT MONO (-8625 4925);
DISPLAY INVISIBLE (-8625 4925);
FORCEPROP 1 LAST PATH I45
J 0
(-8675 5075);
DISPLAY 0.978723 (-8675 5075);
PAINT WHITE (-8675 5075);
DISPLAY INVISIBLE (-8675 5075);
FORCEPROP 1 LAST PART_NUMBER CS31002JB08
J 0
(-8725 4975);
DISPLAY 0.510638 (-8725 4975);
PAINT SKYBLUE (-8725 4975);
DISPLAY INVISIBLE (-8725 4975);
FORCEADD Q_RES..1
(-8625 4550);
FORCEPROP 1 LAST LOCATION R742
J 0
(-8875 4550);
DISPLAY 0.489362 (-8875 4550);
PAINT SKYBLUE (-8875 4550);
FORCEPROP 2 LAST $SEC 1
J 0
(-8675 4750);
DISPLAY 0.680851 (-8675 4750);
PAINT MONO (-8675 4750);
DISPLAY INVISIBLE (-8675 4750);
FORCEPROP 2 LAST CDS_SEC 1
J 0
(-8675 4750);
DISPLAY 1.021277 (-8675 4750);
DISPLAY INVISIBLE (-8675 4750);
FORCEPROP 1 LASTPIN (-8725 4550) $PN 1
J 0
(-8713 4562);
DISPLAY 0.489362 (-8713 4562);
FORCEPROP 1 LASTPIN (-8525 4550) $PN 2
J 0
(-8563 4562);
DISPLAY 0.489362 (-8563 4562);
FORCEPROP 1 LAST VALUE 10K
J 2
(-8425 4550);
DISPLAY 0.489362 (-8425 4550);
PAINT SKYBLUE (-8425 4550);
FORCEPROP 1 LAST TOLERANCE 5%
J 0
(-8400 4550);
DISPLAY 0.489362 (-8400 4550);
PAINT SKYBLUE (-8400 4550);
FORCEPROP 1 LAST MATERIAL EMPTY
J 0
(-8300 4550);
DISPLAY 0.489362 (-8300 4550);
PAINT RED (-8300 4550);
FORCEPROP 1 LAST PACK_TYPE 0402LF
J 0
(-8725 4625);
DISPLAY 0.510638 (-8725 4625);
PAINT SKYBLUE (-8725 4625);
DISPLAY INVISIBLE (-8725 4625);
FORCEPROP 1 LAST WATTAGE 1/16W
J 2
(-8425 4625);
DISPLAY 0.510638 (-8425 4625);
PAINT SKYBLUE (-8425 4625);
DISPLAY INVISIBLE (-8425 4625);
FORCEPROP 2 LAST CDS_LIB pure_quanta
J 0
(-8625 4550);
PAINT MONO (-8625 4550);
DISPLAY INVISIBLE (-8625 4550);
FORCEPROP 1 LAST PATH I46
J 0
(-8675 4700);
DISPLAY 0.978723 (-8675 4700);
PAINT WHITE (-8675 4700);
DISPLAY INVISIBLE (-8675 4700);
FORCEPROP 1 LAST PART_NUMBER CS31002JB08
J 0
(-8725 4600);
DISPLAY 0.510638 (-8725 4600);
PAINT SKYBLUE (-8725 4600);
DISPLAY INVISIBLE (-8725 4600);
FORCEADD OFFPAGE..2
(-7225 3725);
FORCEPROP 2 LAST $XR3 150 
J 0
(-6766 3725);
DISPLAY 0.638298 (-6766 3725);
PAINT MONO (-6766 3725);
FORCEPROP 2 LAST $XR2 81 
J 0
(-6856 3725);
DISPLAY 0.638298 (-6856 3725);
PAINT MONO (-6856 3725);
FORCEPROP 2 LAST $XR1 76 
J 0
(-6946 3725);
DISPLAY 0.638298 (-6946 3725);
PAINT MONO (-6946 3725);
FORCEPROP 2 LAST $XR0 29 
J 0
(-7036 3725);
DISPLAY 0.638298 (-7036 3725);
PAINT MONO (-7036 3725);
FORCEPROP 2 LAST CDS_LIB standard
J 0
(-7225 3725);
DISPLAY INVISIBLE (-7225 3725);
FORCEPROP 1 LAST OFFPAGE TRUE
J 0
(-6900 3600);
DISPLAY 0.872340 (-6900 3600);
PAINT GREEN (-6900 3600);
DISPLAY INVISIBLE (-6900 3600);
FORCEPROP 1 LAST COMMENT_BODY TRUE
J 0
(-7270 3630);
DISPLAY 0.872340 (-7270 3630);
PAINT GREEN (-7270 3630);
DISPLAY INVISIBLE (-7270 3630);
FORCEPROP 2 LAST PATH I5
J 0
(-6925 3775);
DISPLAY 1.021277 (-6925 3775);
DISPLAY INVISIBLE (-6925 3775);
FORCEADD OFFPAGE..2
(-7225 3350);
FORCEPROP 2 LAST $XR1 29 
J 0
(-6946 3350);
DISPLAY 0.638298 (-6946 3350);
PAINT MONO (-6946 3350);
FORCEPROP 2 LAST $XR0 76 
J 0
(-7036 3350);
DISPLAY 0.638298 (-7036 3350);
PAINT MONO (-7036 3350);
FORCEPROP 2 LAST CDS_LIB standard
J 0
(-7225 3350);
DISPLAY INVISIBLE (-7225 3350);
FORCEPROP 1 LAST OFFPAGE TRUE
J 0
(-6900 3225);
DISPLAY 0.872340 (-6900 3225);
PAINT GREEN (-6900 3225);
DISPLAY INVISIBLE (-6900 3225);
FORCEPROP 1 LAST COMMENT_BODY TRUE
J 0
(-7270 3255);
DISPLAY 0.872340 (-7270 3255);
PAINT GREEN (-7270 3255);
DISPLAY INVISIBLE (-7270 3255);
FORCEPROP 2 LAST PATH I7
J 0
(-6925 3400);
DISPLAY 1.021277 (-6925 3400);
DISPLAY INVISIBLE (-6925 3400);
FORCEADD Q_RES..1
(-8650 3725);
FORCEPROP 1 LAST LOCATION R750
J 0
(-8875 3725);
DISPLAY 0.489362 (-8875 3725);
PAINT SKYBLUE (-8875 3725);
FORCEPROP 0 LAST $SEC 1
J 0
(-8325 3750);
DISPLAY 0.680851 (-8325 3750);
PAINT MONO (-8325 3750);
DISPLAY INVISIBLE (-8325 3750);
FORCEPROP 0 LAST CDS_SEC 1
J 0
(-8325 3750);
DISPLAY 0.680851 (-8325 3750);
DISPLAY INVISIBLE (-8325 3750);
FORCEPROP 1 LASTPIN (-8750 3725) $PN 1
J 0
(-8738 3737);
DISPLAY 0.489362 (-8738 3737);
PAINT MONO (-8738 3737);
FORCEPROP 1 LASTPIN (-8550 3725) $PN 2
J 0
(-8588 3737);
DISPLAY 0.489362 (-8588 3737);
PAINT MONO (-8588 3737);
FORCEPROP 1 LAST VALUE 30K
J 2
(-8475 3725);
DISPLAY 0.489362 (-8475 3725);
PAINT SKYBLUE (-8475 3725);
FORCEPROP 1 LAST TOLERANCE 1%
J 0
(-8425 3725);
DISPLAY 0.489362 (-8425 3725);
PAINT SKYBLUE (-8425 3725);
FORCEPROP 1 LAST MATERIAL CHIP
J 0
(-8325 3725);
DISPLAY 0.489362 (-8325 3725);
PAINT SKYBLUE (-8325 3725);
FORCEPROP 2 LAST CDS_LIB pure_quanta
J 0
(-8650 3725);
DISPLAY INVISIBLE (-8650 3725);
FORCEPROP 1 LAST WATTAGE 1/16W
J 2
(-8450 3800);
DISPLAY 0.510638 (-8450 3800);
PAINT SKYBLUE (-8450 3800);
DISPLAY INVISIBLE (-8450 3800);
FORCEPROP 1 LAST PACK_TYPE 0402LF
J 0
(-8750 3800);
DISPLAY 0.510638 (-8750 3800);
PAINT SKYBLUE (-8750 3800);
DISPLAY INVISIBLE (-8750 3800);
FORCEPROP 1 LAST PATH I74
J 0
(-8700 3875);
DISPLAY 0.978723 (-8700 3875);
PAINT WHITE (-8700 3875);
DISPLAY INVISIBLE (-8700 3875);
FORCEPROP 1 LAST PART_NUMBER CS33002FB02
J 0
(-8750 3775);
DISPLAY 0.510638 (-8750 3775);
PAINT SKYBLUE (-8750 3775);
DISPLAY INVISIBLE (-8750 3775);
FORCEADD Q_RES..1
(-8650 3350);
FORCEPROP 1 LAST LOCATION R753
J 0
(-8875 3350);
DISPLAY 0.489362 (-8875 3350);
PAINT SKYBLUE (-8875 3350);
FORCEPROP 0 LAST $SEC 1
J 0
(-8325 3375);
DISPLAY 0.680851 (-8325 3375);
PAINT MONO (-8325 3375);
DISPLAY INVISIBLE (-8325 3375);
FORCEPROP 0 LAST CDS_SEC 1
J 0
(-8325 3375);
DISPLAY 0.680851 (-8325 3375);
DISPLAY INVISIBLE (-8325 3375);
FORCEPROP 1 LASTPIN (-8750 3350) $PN 1
J 0
(-8738 3362);
DISPLAY 0.489362 (-8738 3362);
PAINT MONO (-8738 3362);
FORCEPROP 1 LASTPIN (-8550 3350) $PN 2
J 0
(-8588 3362);
DISPLAY 0.489362 (-8588 3362);
PAINT MONO (-8588 3362);
FORCEPROP 1 LAST VALUE 10K
J 2
(-8475 3350);
DISPLAY 0.489362 (-8475 3350);
PAINT SKYBLUE (-8475 3350);
FORCEPROP 1 LAST MATERIAL CHIP
J 0
(-8325 3350);
DISPLAY 0.489362 (-8325 3350);
PAINT SKYBLUE (-8325 3350);
FORCEPROP 1 LAST TOLERANCE 5%
J 0
(-8425 3350);
DISPLAY 0.489362 (-8425 3350);
PAINT SKYBLUE (-8425 3350);
FORCEPROP 1 LAST PACK_TYPE 0402LF
J 0
(-8750 3425);
DISPLAY 0.510638 (-8750 3425);
PAINT SKYBLUE (-8750 3425);
DISPLAY INVISIBLE (-8750 3425);
FORCEPROP 1 LAST WATTAGE 1/16W
J 2
(-8450 3425);
DISPLAY 0.510638 (-8450 3425);
PAINT SKYBLUE (-8450 3425);
DISPLAY INVISIBLE (-8450 3425);
FORCEPROP 2 LAST CDS_LIB pure_quanta
J 0
(-8650 3350);
DISPLAY INVISIBLE (-8650 3350);
FORCEPROP 1 LAST PATH I75
J 0
(-8700 3500);
DISPLAY 0.978723 (-8700 3500);
PAINT WHITE (-8700 3500);
DISPLAY INVISIBLE (-8700 3500);
FORCEPROP 1 LAST PART_NUMBER CS31002JB08
J 0
(-8750 3400);
DISPLAY 0.510638 (-8750 3400);
PAINT SKYBLUE (-8750 3400);
DISPLAY INVISIBLE (-8750 3400);
FORCEADD Q_RES..1
(-8650 4250);
FORCEPROP 1 LAST LOCATION R747
J 0
(-8875 4250);
DISPLAY 0.489362 (-8875 4250);
PAINT SKYBLUE (-8875 4250);
FORCEPROP 2 LAST $SEC 1
J 0
(-8700 4450);
DISPLAY 0.680851 (-8700 4450);
PAINT MONO (-8700 4450);
DISPLAY INVISIBLE (-8700 4450);
FORCEPROP 2 LAST CDS_SEC 1
J 0
(-8700 4450);
DISPLAY 1.021277 (-8700 4450);
DISPLAY INVISIBLE (-8700 4450);
FORCEPROP 1 LASTPIN (-8750 4250) $PN 1
J 0
(-8738 4262);
DISPLAY 0.489362 (-8738 4262);
FORCEPROP 1 LASTPIN (-8550 4250) $PN 2
J 0
(-8588 4262);
DISPLAY 0.489362 (-8588 4262);
FORCEPROP 1 LAST TOLERANCE 1%
J 0
(-8425 4250);
DISPLAY 0.489362 (-8425 4250);
PAINT SKYBLUE (-8425 4250);
FORCEPROP 1 LAST VALUE 1K
J 2
(-8450 4250);
DISPLAY 0.489362 (-8450 4250);
PAINT SKYBLUE (-8450 4250);
FORCEPROP 1 LAST MATERIAL CHIP
J 0
(-8325 4250);
DISPLAY 0.489362 (-8325 4250);
PAINT SKYBLUE (-8325 4250);
FORCEPROP 1 LAST PACK_TYPE 0402LF
J 0
(-8750 4325);
DISPLAY 0.510638 (-8750 4325);
PAINT SKYBLUE (-8750 4325);
DISPLAY INVISIBLE (-8750 4325);
FORCEPROP 1 LAST WATTAGE 1/16W
J 2
(-8475 4325);
DISPLAY 0.510638 (-8475 4325);
PAINT SKYBLUE (-8475 4325);
DISPLAY INVISIBLE (-8475 4325);
FORCEPROP 2 LAST CDS_LIB pure_quanta
J 0
(-8650 4250);
PAINT MONO (-8650 4250);
DISPLAY INVISIBLE (-8650 4250);
FORCEPROP 1 LAST PATH I8
J 0
(-8700 4400);
DISPLAY 0.978723 (-8700 4400);
PAINT WHITE (-8700 4400);
DISPLAY INVISIBLE (-8700 4400);
FORCEPROP 1 LAST PART_NUMBER CS21002FB06
J 0
(-8750 4300);
DISPLAY 0.510638 (-8750 4300);
PAINT SKYBLUE (-8750 4300);
DISPLAY INVISIBLE (-8750 4300);
FORCEADD OFFPAGE..2
(-2525 5550);
FORCEPROP 2 LAST $XR1 76 
J 0
(-2246 5550);
DISPLAY 0.638298 (-2246 5550);
PAINT MONO (-2246 5550);
FORCEPROP 2 LAST $XR0 56 
J 0
(-2336 5550);
DISPLAY 0.638298 (-2336 5550);
PAINT MONO (-2336 5550);
FORCEPROP 2 LAST CDS_LIB standard
J 0
(-2525 5550);
DISPLAY INVISIBLE (-2525 5550);
FORCEPROP 1 LAST OFFPAGE TRUE
J 0
(-2200 5425);
DISPLAY 0.872340 (-2200 5425);
PAINT GREEN (-2200 5425);
DISPLAY INVISIBLE (-2200 5425);
FORCEPROP 1 LAST COMMENT_BODY TRUE
J 0
(-2570 5455);
DISPLAY 0.872340 (-2570 5455);
PAINT GREEN (-2570 5455);
DISPLAY INVISIBLE (-2570 5455);
FORCEPROP 2 LAST PATH I80
J 0
(-2325 5600);
DISPLAY 0.680851 (-2325 5600);
DISPLAY INVISIBLE (-2325 5600);
FORCEADD OFFPAGE..2
(-2525 5275);
FORCEPROP 2 LAST $XR1 56 
J 0
(-2246 5275);
DISPLAY 0.638298 (-2246 5275);
PAINT MONO (-2246 5275);
FORCEPROP 2 LAST $XR0 76 
J 0
(-2336 5275);
DISPLAY 0.638298 (-2336 5275);
PAINT MONO (-2336 5275);
FORCEPROP 2 LAST CDS_LIB standard
J 0
(-2525 5275);
DISPLAY INVISIBLE (-2525 5275);
FORCEPROP 1 LAST OFFPAGE TRUE
J 0
(-2200 5150);
DISPLAY 0.872340 (-2200 5150);
PAINT GREEN (-2200 5150);
DISPLAY INVISIBLE (-2200 5150);
FORCEPROP 1 LAST COMMENT_BODY TRUE
J 0
(-2570 5180);
DISPLAY 0.872340 (-2570 5180);
PAINT GREEN (-2570 5180);
DISPLAY INVISIBLE (-2570 5180);
FORCEPROP 2 LAST PATH I81
J 0
(-2225 5325);
DISPLAY 0.680851 (-2225 5325);
DISPLAY INVISIBLE (-2225 5325);
FORCEADD OFFPAGE..2
(-2525 5000);
FORCEPROP 2 LAST $XR1 76 
J 0
(-2246 5000);
DISPLAY 0.638298 (-2246 5000);
PAINT MONO (-2246 5000);
FORCEPROP 2 LAST $XR0 55 
J 0
(-2336 5000);
DISPLAY 0.638298 (-2336 5000);
PAINT MONO (-2336 5000);
FORCEPROP 2 LAST CDS_LIB standard
J 0
(-2525 5000);
DISPLAY INVISIBLE (-2525 5000);
FORCEPROP 1 LAST OFFPAGE TRUE
J 0
(-2200 4875);
DISPLAY 0.872340 (-2200 4875);
PAINT GREEN (-2200 4875);
DISPLAY INVISIBLE (-2200 4875);
FORCEPROP 1 LAST COMMENT_BODY TRUE
J 0
(-2570 4905);
DISPLAY 0.872340 (-2570 4905);
PAINT GREEN (-2570 4905);
DISPLAY INVISIBLE (-2570 4905);
FORCEPROP 2 LAST PATH I82
J 0
(-2225 5050);
DISPLAY 0.680851 (-2225 5050);
DISPLAY INVISIBLE (-2225 5050);
FORCEADD OFFPAGE..2
(-2525 4650);
FORCEPROP 2 LAST $XR1 76 
J 0
(-2246 4650);
DISPLAY 0.638298 (-2246 4650);
PAINT MONO (-2246 4650);
FORCEPROP 2 LAST $XR0 56 
J 0
(-2336 4650);
DISPLAY 0.638298 (-2336 4650);
PAINT MONO (-2336 4650);
FORCEPROP 2 LAST CDS_LIB standard
J 0
(-2525 4650);
DISPLAY INVISIBLE (-2525 4650);
FORCEPROP 1 LAST OFFPAGE TRUE
J 0
(-2200 4525);
DISPLAY 0.872340 (-2200 4525);
PAINT GREEN (-2200 4525);
DISPLAY INVISIBLE (-2200 4525);
FORCEPROP 1 LAST COMMENT_BODY TRUE
J 0
(-2570 4555);
DISPLAY 0.872340 (-2570 4555);
PAINT GREEN (-2570 4555);
DISPLAY INVISIBLE (-2570 4555);
FORCEPROP 2 LAST PATH I83
J 0
(-2325 4700);
DISPLAY 0.680851 (-2325 4700);
DISPLAY INVISIBLE (-2325 4700);
FORCEADD OFFPAGE..2
(-2525 4375);
FORCEPROP 2 LAST $XR1 56 
J 0
(-2246 4375);
DISPLAY 0.638298 (-2246 4375);
PAINT MONO (-2246 4375);
FORCEPROP 2 LAST $XR0 76 
J 0
(-2336 4375);
DISPLAY 0.638298 (-2336 4375);
PAINT MONO (-2336 4375);
FORCEPROP 2 LAST CDS_LIB standard
J 0
(-2525 4375);
DISPLAY INVISIBLE (-2525 4375);
FORCEPROP 1 LAST OFFPAGE TRUE
J 0
(-2200 4250);
DISPLAY 0.872340 (-2200 4250);
PAINT GREEN (-2200 4250);
DISPLAY INVISIBLE (-2200 4250);
FORCEPROP 1 LAST COMMENT_BODY TRUE
J 0
(-2570 4280);
DISPLAY 0.872340 (-2570 4280);
PAINT GREEN (-2570 4280);
DISPLAY INVISIBLE (-2570 4280);
FORCEPROP 2 LAST PATH I84
J 0
(-2225 4425);
DISPLAY 0.680851 (-2225 4425);
DISPLAY INVISIBLE (-2225 4425);
FORCEADD Q_RES..1
(-3950 5550);
FORCEPROP 1 LAST LOCATION R730
J 0
(-4000 5600);
DISPLAY 0.489362 (-4000 5600);
PAINT SKYBLUE (-4000 5600);
FORCEPROP 0 LAST $SEC 1
J 0
(-4000 5650);
DISPLAY 0.680851 (-4000 5650);
PAINT MONO (-4000 5650);
DISPLAY INVISIBLE (-4000 5650);
FORCEPROP 0 LAST CDS_SEC 1
J 0
(-4000 5650);
DISPLAY 0.680851 (-4000 5650);
DISPLAY INVISIBLE (-4000 5650);
FORCEPROP 1 LASTPIN (-4050 5550) $PN 1
J 0
(-4038 5562);
DISPLAY 0.489362 (-4038 5562);
PAINT MONO (-4038 5562);
FORCEPROP 1 LASTPIN (-3850 5550) $PN 2
J 0
(-3888 5562);
DISPLAY 0.489362 (-3888 5562);
PAINT MONO (-3888 5562);
FORCEPROP 1 LAST MATERIAL CHIP
J 0
(-3625 5550);
DISPLAY 0.489362 (-3625 5550);
PAINT SKYBLUE (-3625 5550);
FORCEPROP 1 LAST VALUE 10K
J 2
(-3775 5550);
DISPLAY 0.489362 (-3775 5550);
PAINT SKYBLUE (-3775 5550);
FORCEPROP 1 LAST TOLERANCE 5%
J 0
(-3725 5550);
DISPLAY 0.489362 (-3725 5550);
PAINT SKYBLUE (-3725 5550);
FORCEPROP 2 LAST CDS_LIB pure_quanta
J 0
(-3950 5550);
DISPLAY INVISIBLE (-3950 5550);
FORCEPROP 1 LAST WATTAGE 1/16W
J 2
(-3750 5625);
DISPLAY 0.510638 (-3750 5625);
PAINT SKYBLUE (-3750 5625);
DISPLAY INVISIBLE (-3750 5625);
FORCEPROP 1 LAST PACK_TYPE 0402LF
J 0
(-4050 5625);
DISPLAY 0.510638 (-4050 5625);
PAINT SKYBLUE (-4050 5625);
DISPLAY INVISIBLE (-4050 5625);
FORCEPROP 1 LAST PATH I87
J 0
(-4000 5700);
DISPLAY 0.978723 (-4000 5700);
PAINT WHITE (-4000 5700);
DISPLAY INVISIBLE (-4000 5700);
FORCEPROP 1 LAST PART_NUMBER CS31002JB08
J 0
(-4050 5600);
DISPLAY 0.510638 (-4050 5600);
PAINT SKYBLUE (-4050 5600);
DISPLAY INVISIBLE (-4050 5600);
FORCEADD UNIVERSAL_POWER..1
(-4275 5800);
FORCEPROP 3 LASTPIN (-4275 5750) SIG_NAME PVDD18_S5_P1\g
J 0
(-4265 5760);
DISPLAY 0.659574 (-4265 5760);
PAINT MONO (-4265 5760);
DISPLAY INVISIBLE (-4265 5760);
FORCEPROP 1 LAST HDL_POWER PVDD18_S5_P1
J 1
(-4275 5850);
DISPLAY 0.489362 (-4275 5850);
PAINT GREEN (-4275 5850);
FORCEPROP 2 LAST CDS_LIB pure_quanta_power
J 0
(-4275 5800);
DISPLAY INVISIBLE (-4275 5800);
FORCEPROP 1 LAST PATH I88
J 0
(-4225 5825);
DISPLAY 0.872340 (-4225 5825);
PAINT AQUA (-4225 5825);
DISPLAY INVISIBLE (-4225 5825);
FORCEADD Q_RES..1
(-3975 5275);
FORCEPROP 1 LAST LOCATION R736
J 0
(-4200 5275);
DISPLAY 0.489362 (-4200 5275);
PAINT SKYBLUE (-4200 5275);
FORCEPROP 2 LAST $SEC 1
J 0
(-4025 5475);
DISPLAY 0.680851 (-4025 5475);
PAINT MONO (-4025 5475);
DISPLAY INVISIBLE (-4025 5475);
FORCEPROP 2 LAST CDS_SEC 1
J 0
(-4025 5475);
DISPLAY 1.021277 (-4025 5475);
DISPLAY INVISIBLE (-4025 5475);
FORCEPROP 1 LASTPIN (-4075 5275) $PN 1
J 0
(-4063 5287);
DISPLAY 0.489362 (-4063 5287);
FORCEPROP 1 LASTPIN (-3875 5275) $PN 2
J 0
(-3913 5287);
DISPLAY 0.489362 (-3913 5287);
FORCEPROP 1 LAST MATERIAL EMPTY
J 0
(-3650 5275);
DISPLAY 0.489362 (-3650 5275);
PAINT RED (-3650 5275);
FORCEPROP 1 LAST VALUE 10K
J 2
(-3775 5275);
DISPLAY 0.489362 (-3775 5275);
PAINT SKYBLUE (-3775 5275);
FORCEPROP 1 LAST TOLERANCE 5%
J 0
(-3750 5275);
DISPLAY 0.489362 (-3750 5275);
PAINT SKYBLUE (-3750 5275);
FORCEPROP 1 LAST PACK_TYPE 0402LF
J 0
(-4075 5350);
DISPLAY 0.510638 (-4075 5350);
PAINT SKYBLUE (-4075 5350);
DISPLAY INVISIBLE (-4075 5350);
FORCEPROP 1 LAST WATTAGE 1/16W
J 2
(-3775 5350);
DISPLAY 0.510638 (-3775 5350);
PAINT SKYBLUE (-3775 5350);
DISPLAY INVISIBLE (-3775 5350);
FORCEPROP 2 LAST CDS_LIB pure_quanta
J 0
(-3975 5275);
PAINT MONO (-3975 5275);
DISPLAY INVISIBLE (-3975 5275);
FORCEPROP 1 LAST PATH I89
J 0
(-4025 5425);
DISPLAY 0.978723 (-4025 5425);
PAINT WHITE (-4025 5425);
DISPLAY INVISIBLE (-4025 5425);
FORCEPROP 1 LAST PART_NUMBER CS31002JB08
J 0
(-4075 5325);
DISPLAY 0.510638 (-4075 5325);
PAINT SKYBLUE (-4075 5325);
DISPLAY INVISIBLE (-4075 5325);
FORCEADD Q_RES..1
(-8650 3975);
FORCEPROP 1 LAST LOCATION R748
J 0
(-8875 3975);
DISPLAY 0.489362 (-8875 3975);
PAINT SKYBLUE (-8875 3975);
FORCEPROP 2 LAST $SEC 1
J 0
(-8700 4175);
DISPLAY 0.680851 (-8700 4175);
PAINT MONO (-8700 4175);
DISPLAY INVISIBLE (-8700 4175);
FORCEPROP 2 LAST CDS_SEC 1
J 0
(-8700 4175);
DISPLAY 1.021277 (-8700 4175);
DISPLAY INVISIBLE (-8700 4175);
FORCEPROP 1 LASTPIN (-8750 3975) $PN 1
J 0
(-8738 3987);
DISPLAY 0.489362 (-8738 3987);
FORCEPROP 1 LASTPIN (-8550 3975) $PN 2
J 0
(-8588 3987);
DISPLAY 0.489362 (-8588 3987);
FORCEPROP 1 LAST VALUE 10K
J 2
(-8450 3975);
DISPLAY 0.489362 (-8450 3975);
PAINT SKYBLUE (-8450 3975);
FORCEPROP 1 LAST TOLERANCE 5%
J 0
(-8425 3975);
DISPLAY 0.489362 (-8425 3975);
PAINT SKYBLUE (-8425 3975);
FORCEPROP 1 LAST MATERIAL EMPTY
J 0
(-8325 3975);
DISPLAY 0.489362 (-8325 3975);
PAINT RED (-8325 3975);
FORCEPROP 1 LAST PACK_TYPE 0402LF
J 0
(-8750 4050);
DISPLAY 0.510638 (-8750 4050);
PAINT SKYBLUE (-8750 4050);
DISPLAY INVISIBLE (-8750 4050);
FORCEPROP 1 LAST WATTAGE 1/16W
J 2
(-8475 4050);
DISPLAY 0.510638 (-8475 4050);
PAINT SKYBLUE (-8475 4050);
DISPLAY INVISIBLE (-8475 4050);
FORCEPROP 2 LAST CDS_LIB pure_quanta
J 0
(-8650 3975);
PAINT MONO (-8650 3975);
DISPLAY INVISIBLE (-8650 3975);
FORCEPROP 1 LAST PATH I9
J 0
(-8700 4125);
DISPLAY 0.978723 (-8700 4125);
PAINT WHITE (-8700 4125);
DISPLAY INVISIBLE (-8700 4125);
FORCEPROP 1 LAST PART_NUMBER CS31002JB08
J 0
(-8750 4025);
DISPLAY 0.510638 (-8750 4025);
PAINT SKYBLUE (-8750 4025);
DISPLAY INVISIBLE (-8750 4025);
FORCEADD Q_RES..1
(-3950 5000);
FORCEPROP 1 LAST LOCATION R1501
J 0
(-4200 5000);
DISPLAY 0.489362 (-4200 5000);
PAINT SKYBLUE (-4200 5000);
FORCEPROP 2 LAST $SEC 1
J 0
(-4000 5200);
DISPLAY 0.680851 (-4000 5200);
PAINT MONO (-4000 5200);
DISPLAY INVISIBLE (-4000 5200);
FORCEPROP 2 LAST CDS_SEC 1
J 0
(-4000 5200);
DISPLAY 1.021277 (-4000 5200);
DISPLAY INVISIBLE (-4000 5200);
FORCEPROP 1 LASTPIN (-4050 5000) $PN 1
J 0
(-4038 5012);
DISPLAY 0.489362 (-4038 5012);
FORCEPROP 1 LASTPIN (-3850 5000) $PN 2
J 0
(-3888 5012);
DISPLAY 0.489362 (-3888 5012);
FORCEPROP 1 LAST VALUE 10K
J 2
(-3750 5000);
DISPLAY 0.489362 (-3750 5000);
PAINT SKYBLUE (-3750 5000);
FORCEPROP 1 LAST TOLERANCE 5%
J 0
(-3725 5000);
DISPLAY 0.489362 (-3725 5000);
PAINT SKYBLUE (-3725 5000);
FORCEPROP 1 LAST MATERIAL EMPTY
J 0
(-3625 5000);
DISPLAY 0.489362 (-3625 5000);
PAINT RED (-3625 5000);
FORCEPROP 1 LAST PACK_TYPE 0402LF
J 0
(-4050 5075);
DISPLAY 0.510638 (-4050 5075);
PAINT SKYBLUE (-4050 5075);
DISPLAY INVISIBLE (-4050 5075);
FORCEPROP 1 LAST WATTAGE 1/16W
J 2
(-3775 5075);
DISPLAY 0.510638 (-3775 5075);
PAINT SKYBLUE (-3775 5075);
DISPLAY INVISIBLE (-3775 5075);
FORCEPROP 2 LAST CDS_LIB pure_quanta
J 0
(-3950 5000);
PAINT MONO (-3950 5000);
DISPLAY INVISIBLE (-3950 5000);
FORCEPROP 1 LAST PATH I90
J 0
(-4000 5150);
DISPLAY 0.978723 (-4000 5150);
PAINT WHITE (-4000 5150);
DISPLAY INVISIBLE (-4000 5150);
FORCEPROP 1 LAST PART_NUMBER CS31002JB08
J 0
(-4050 5050);
DISPLAY 0.510638 (-4050 5050);
PAINT SKYBLUE (-4050 5050);
DISPLAY INVISIBLE (-4050 5050);
FORCEADD Q_RES..1
(-3925 4650);
FORCEPROP 1 LAST LOCATION R754
J 0
(-4150 4650);
DISPLAY 0.489362 (-4150 4650);
PAINT SKYBLUE (-4150 4650);
FORCEPROP 2 LAST $SEC 1
J 0
(-3975 4850);
DISPLAY 0.680851 (-3975 4850);
PAINT MONO (-3975 4850);
DISPLAY INVISIBLE (-3975 4850);
FORCEPROP 2 LAST CDS_SEC 1
J 0
(-3975 4850);
DISPLAY 1.021277 (-3975 4850);
DISPLAY INVISIBLE (-3975 4850);
FORCEPROP 1 LASTPIN (-4025 4650) $PN 1
J 0
(-4013 4662);
DISPLAY 0.489362 (-4013 4662);
FORCEPROP 1 LASTPIN (-3825 4650) $PN 2
J 0
(-3863 4662);
DISPLAY 0.489362 (-3863 4662);
FORCEPROP 1 LAST TOLERANCE 5%
J 0
(-3700 4650);
DISPLAY 0.489362 (-3700 4650);
PAINT SKYBLUE (-3700 4650);
FORCEPROP 1 LAST WATTAGE 1/16W
J 2
(-3750 4725);
DISPLAY 0.489362 (-3750 4725);
PAINT SKYBLUE (-3750 4725);
FORCEPROP 1 LAST VALUE 10K
J 2
(-3725 4650);
DISPLAY 0.489362 (-3725 4650);
PAINT SKYBLUE (-3725 4650);
FORCEPROP 1 LAST PACK_TYPE 0402LF
J 0
(-4025 4725);
DISPLAY 0.489362 (-4025 4725);
PAINT SKYBLUE (-4025 4725);
FORCEPROP 1 LAST MATERIAL EMPTY
J 0
(-3600 4650);
DISPLAY 0.489362 (-3600 4650);
PAINT RED (-3600 4650);
FORCEPROP 2 LAST CDS_LIB pure_quanta
J 0
(-3925 4650);
PAINT MONO (-3925 4650);
DISPLAY INVISIBLE (-3925 4650);
FORCEPROP 1 LAST PATH I91
J 0
(-3975 4800);
DISPLAY 0.978723 (-3975 4800);
PAINT WHITE (-3975 4800);
DISPLAY INVISIBLE (-3975 4800);
FORCEPROP 1 LAST PART_NUMBER CS31002JB08
J 0
(-4025 4700);
DISPLAY 0.489362 (-4025 4700);
PAINT SKYBLUE (-4025 4700);
DISPLAY INVISIBLE (-4025 4700);
FORCEADD Q_RES..1
(-3950 4375);
FORCEPROP 1 LAST LOCATION R760
J 0
(-4175 4375);
DISPLAY 0.489362 (-4175 4375);
PAINT SKYBLUE (-4175 4375);
FORCEPROP 0 LAST $SEC 1
J 0
(-4175 4425);
DISPLAY 0.680851 (-4175 4425);
PAINT MONO (-4175 4425);
DISPLAY INVISIBLE (-4175 4425);
FORCEPROP 0 LAST CDS_SEC 1
J 0
(-4175 4425);
DISPLAY 0.680851 (-4175 4425);
DISPLAY INVISIBLE (-4175 4425);
FORCEPROP 1 LASTPIN (-4050 4375) $PN 1
J 0
(-4038 4387);
DISPLAY 0.489362 (-4038 4387);
PAINT MONO (-4038 4387);
FORCEPROP 1 LASTPIN (-3850 4375) $PN 2
J 0
(-3888 4387);
DISPLAY 0.489362 (-3888 4387);
PAINT MONO (-3888 4387);
FORCEPROP 1 LAST VALUE 10K
J 2
(-3775 4375);
DISPLAY 0.489362 (-3775 4375);
PAINT SKYBLUE (-3775 4375);
FORCEPROP 1 LAST TOLERANCE 5%
J 0
(-3725 4375);
DISPLAY 0.489362 (-3725 4375);
PAINT SKYBLUE (-3725 4375);
FORCEPROP 1 LAST MATERIAL CHIP
J 0
(-3625 4375);
DISPLAY 0.489362 (-3625 4375);
PAINT SKYBLUE (-3625 4375);
FORCEPROP 1 LAST PACK_TYPE 0402LF
J 0
(-4050 4450);
DISPLAY 0.510638 (-4050 4450);
PAINT SKYBLUE (-4050 4450);
DISPLAY INVISIBLE (-4050 4450);
FORCEPROP 1 LAST WATTAGE 1/16W
J 2
(-3750 4450);
DISPLAY 0.510638 (-3750 4450);
PAINT SKYBLUE (-3750 4450);
DISPLAY INVISIBLE (-3750 4450);
FORCEPROP 2 LAST CDS_LIB pure_quanta
J 0
(-3950 4375);
DISPLAY INVISIBLE (-3950 4375);
FORCEPROP 1 LAST PATH I92
J 0
(-4000 4525);
DISPLAY 0.978723 (-4000 4525);
PAINT WHITE (-4000 4525);
DISPLAY INVISIBLE (-4000 4525);
FORCEPROP 1 LAST PART_NUMBER CS31002JB08
J 0
(-4050 4425);
DISPLAY 0.510638 (-4050 4425);
PAINT SKYBLUE (-4050 4425);
DISPLAY INVISIBLE (-4050 4425);
FORCEADD OFFPAGE..2
(-2525 4100);
FORCEPROP 2 LAST $XR1 76 
J 0
(-2246 4100);
DISPLAY 0.638298 (-2246 4100);
PAINT MONO (-2246 4100);
FORCEPROP 2 LAST $XR0 55 
J 0
(-2336 4100);
DISPLAY 0.638298 (-2336 4100);
PAINT MONO (-2336 4100);
FORCEPROP 2 LAST CDS_LIB standard
J 0
(-2525 4100);
DISPLAY INVISIBLE (-2525 4100);
FORCEPROP 1 LAST OFFPAGE TRUE
J 0
(-2200 3975);
DISPLAY 0.872340 (-2200 3975);
PAINT GREEN (-2200 3975);
DISPLAY INVISIBLE (-2200 3975);
FORCEPROP 1 LAST COMMENT_BODY TRUE
J 0
(-2570 4005);
DISPLAY 0.872340 (-2570 4005);
PAINT GREEN (-2570 4005);
DISPLAY INVISIBLE (-2570 4005);
FORCEPROP 2 LAST PATH I93
J 0
(-2225 4150);
DISPLAY 0.680851 (-2225 4150);
DISPLAY INVISIBLE (-2225 4150);
FORCEADD Q_RES..1
(-3950 4100);
FORCEPROP 1 LAST LOCATION R1502
J 0
(-4175 4100);
DISPLAY 0.489362 (-4175 4100);
PAINT SKYBLUE (-4175 4100);
FORCEPROP 2 LAST $SEC 1
J 0
(-4000 4300);
DISPLAY 0.680851 (-4000 4300);
PAINT MONO (-4000 4300);
DISPLAY INVISIBLE (-4000 4300);
FORCEPROP 2 LAST CDS_SEC 1
J 0
(-4000 4300);
DISPLAY 1.021277 (-4000 4300);
DISPLAY INVISIBLE (-4000 4300);
FORCEPROP 1 LASTPIN (-4050 4100) $PN 1
J 0
(-4038 4112);
DISPLAY 0.489362 (-4038 4112);
FORCEPROP 1 LASTPIN (-3850 4100) $PN 2
J 0
(-3888 4112);
DISPLAY 0.489362 (-3888 4112);
FORCEPROP 1 LAST VALUE 10K
J 2
(-3750 4100);
DISPLAY 0.489362 (-3750 4100);
PAINT SKYBLUE (-3750 4100);
FORCEPROP 1 LAST TOLERANCE 5%
J 0
(-3725 4100);
DISPLAY 0.489362 (-3725 4100);
PAINT SKYBLUE (-3725 4100);
FORCEPROP 1 LAST MATERIAL CHIP
J 0
(-3625 4100);
DISPLAY 0.489362 (-3625 4100);
PAINT SKYBLUE (-3625 4100);
FORCEPROP 1 LAST PACK_TYPE 0402LF
J 0
(-4050 4175);
DISPLAY 0.510638 (-4050 4175);
PAINT SKYBLUE (-4050 4175);
DISPLAY INVISIBLE (-4050 4175);
FORCEPROP 1 LAST WATTAGE 1/16W
J 2
(-3775 4175);
DISPLAY 0.510638 (-3775 4175);
PAINT SKYBLUE (-3775 4175);
DISPLAY INVISIBLE (-3775 4175);
FORCEPROP 2 LAST CDS_LIB pure_quanta
J 0
(-3950 4100);
PAINT MONO (-3950 4100);
DISPLAY INVISIBLE (-3950 4100);
FORCEPROP 1 LAST PATH I94
J 0
(-4000 4250);
DISPLAY 0.978723 (-4000 4250);
PAINT WHITE (-4000 4250);
DISPLAY INVISIBLE (-4000 4250);
FORCEPROP 1 LAST PART_NUMBER CS31002JB08
J 0
(-4050 4150);
DISPLAY 0.510638 (-4050 4150);
PAINT SKYBLUE (-4050 4150);
DISPLAY INVISIBLE (-4050 4150);
FORCEADD UNIVERSAL_GND..1
(-4275 3725);
FORCEPROP 3 LASTPIN (-4275 3775) SIG_NAME GND\g
J 0
(-4265 3785);
DISPLAY 0.659574 (-4265 3785);
PAINT MONO (-4265 3785);
DISPLAY INVISIBLE (-4265 3785);
FORCEPROP 2 LAST CDS_LIB pure_quanta_power
J 0
(-4275 3725);
DISPLAY INVISIBLE (-4275 3725);
FORCEPROP 1 LAST HDL_POWER GND
J 1
(-4250 3650);
DISPLAY 0.872340 (-4250 3650);
PAINT GREEN (-4250 3650);
DISPLAY INVISIBLE (-4250 3650);
FORCEPROP 1 LAST PATH I95
J 0
(-4200 3725);
DISPLAY 0.872340 (-4200 3725);
PAINT AQUA (-4200 3725);
DISPLAY INVISIBLE (-4200 3725);
FORCEADD OFFPAGE..2
(-7225 5725);
FORCEPROP 2 LAST $XR2 77 
J 0
(-6856 5725);
DISPLAY 0.638298 (-6856 5725);
PAINT MONO (-6856 5725);
FORCEPROP 2 LAST $XR1 76 
J 0
(-6946 5725);
DISPLAY 0.638298 (-6946 5725);
PAINT MONO (-6946 5725);
FORCEPROP 2 LAST $XR0 29 
J 0
(-7036 5725);
DISPLAY 0.638298 (-7036 5725);
PAINT MONO (-7036 5725);
FORCEPROP 2 LAST CDS_LIB standard
J 0
(-7225 5725);
DISPLAY INVISIBLE (-7225 5725);
FORCEPROP 1 LAST OFFPAGE TRUE
J 0
(-6900 5600);
DISPLAY 0.872340 (-6900 5600);
PAINT GREEN (-6900 5600);
DISPLAY INVISIBLE (-6900 5600);
FORCEPROP 1 LAST COMMENT_BODY TRUE
J 0
(-7270 5630);
DISPLAY 0.872340 (-7270 5630);
PAINT GREEN (-7270 5630);
DISPLAY INVISIBLE (-7270 5630);
FORCEPROP 2 LAST PATH I96
J 0
(-6925 5775);
DISPLAY 0.680851 (-6925 5775);
DISPLAY INVISIBLE (-6925 5775);
FORCEADD Q_RES..1
(-8625 5725);
FORCEPROP 1 LAST LOCATION R743
J 0
(-8875 5725);
DISPLAY 0.489362 (-8875 5725);
PAINT SKYBLUE (-8875 5725);
FORCEPROP 2 LAST $SEC 1
J 0
(-8675 5925);
DISPLAY 0.680851 (-8675 5925);
PAINT MONO (-8675 5925);
DISPLAY INVISIBLE (-8675 5925);
FORCEPROP 2 LAST CDS_SEC 1
J 0
(-8675 5925);
DISPLAY 1.021277 (-8675 5925);
DISPLAY INVISIBLE (-8675 5925);
FORCEPROP 1 LASTPIN (-8725 5725) $PN 1
J 0
(-8713 5737);
DISPLAY 0.489362 (-8713 5737);
FORCEPROP 1 LASTPIN (-8525 5725) $PN 2
J 0
(-8563 5737);
DISPLAY 0.489362 (-8563 5737);
FORCEPROP 1 LAST TOLERANCE 5%
J 0
(-8400 5725);
DISPLAY 0.489362 (-8400 5725);
PAINT SKYBLUE (-8400 5725);
FORCEPROP 1 LAST MATERIAL CHIP
J 0
(-8300 5725);
DISPLAY 0.489362 (-8300 5725);
PAINT SKYBLUE (-8300 5725);
FORCEPROP 1 LAST VALUE 10K
J 2
(-8425 5725);
DISPLAY 0.489362 (-8425 5725);
PAINT SKYBLUE (-8425 5725);
FORCEPROP 1 LAST PACK_TYPE 0402LF
J 0
(-8725 5800);
DISPLAY 0.510638 (-8725 5800);
PAINT SKYBLUE (-8725 5800);
DISPLAY INVISIBLE (-8725 5800);
FORCEPROP 1 LAST WATTAGE 1/16W
J 2
(-8425 5800);
DISPLAY 0.510638 (-8425 5800);
PAINT SKYBLUE (-8425 5800);
DISPLAY INVISIBLE (-8425 5800);
FORCEPROP 2 LAST CDS_LIB pure_quanta
J 0
(-8625 5725);
PAINT MONO (-8625 5725);
DISPLAY INVISIBLE (-8625 5725);
FORCEPROP 1 LAST PATH I97
J 0
(-8675 5875);
DISPLAY 0.978723 (-8675 5875);
PAINT WHITE (-8675 5875);
DISPLAY INVISIBLE (-8675 5875);
FORCEPROP 1 LAST PART_NUMBER CS31002JB08
J 0
(-8725 5775);
DISPLAY 0.510638 (-8725 5775);
PAINT SKYBLUE (-8725 5775);
DISPLAY INVISIBLE (-8725 5775);
FORCEADD OFFPAGE..2
(-7225 3150);
FORCEPROP 2 LAST $XR2 77 
J 0
(-6856 3150);
DISPLAY 0.638298 (-6856 3150);
PAINT MONO (-6856 3150);
FORCEPROP 2 LAST $XR1 76 
J 0
(-6946 3150);
DISPLAY 0.638298 (-6946 3150);
PAINT MONO (-6946 3150);
FORCEPROP 2 LAST $XR0 29 
J 0
(-7036 3150);
DISPLAY 0.638298 (-7036 3150);
PAINT MONO (-7036 3150);
FORCEPROP 2 LAST CDS_LIB standard
J 0
(-7225 3150);
DISPLAY INVISIBLE (-7225 3150);
FORCEPROP 1 LAST OFFPAGE TRUE
J 0
(-6900 3025);
DISPLAY 0.872340 (-6900 3025);
PAINT GREEN (-6900 3025);
DISPLAY INVISIBLE (-6900 3025);
FORCEPROP 1 LAST COMMENT_BODY TRUE
J 0
(-7270 3055);
DISPLAY 0.872340 (-7270 3055);
PAINT GREEN (-7270 3055);
DISPLAY INVISIBLE (-7270 3055);
FORCEPROP 2 LAST PATH I98
J 0
(-7050 3225);
DISPLAY 0.680851 (-7050 3225);
DISPLAY INVISIBLE (-7050 3225);
FORCEADD Q_RES..1
(-8625 3150);
FORCEPROP 1 LAST LOCATION R6098
J 0
(-8875 3150);
DISPLAY 0.489362 (-8875 3150);
PAINT SKYBLUE (-8875 3150);
FORCEPROP 2 LAST $SEC 1
J 0
(-8675 3350);
DISPLAY 0.680851 (-8675 3350);
PAINT MONO (-8675 3350);
DISPLAY INVISIBLE (-8675 3350);
FORCEPROP 2 LAST CDS_SEC 1
J 0
(-8675 3350);
DISPLAY 1.021277 (-8675 3350);
DISPLAY INVISIBLE (-8675 3350);
FORCEPROP 1 LASTPIN (-8725 3150) $PN 1
J 0
(-8713 3162);
DISPLAY 0.489362 (-8713 3162);
FORCEPROP 1 LASTPIN (-8525 3150) $PN 2
J 0
(-8563 3162);
DISPLAY 0.489362 (-8563 3162);
FORCEPROP 1 LAST VALUE 10K
J 2
(-8425 3150);
DISPLAY 0.489362 (-8425 3150);
PAINT SKYBLUE (-8425 3150);
FORCEPROP 1 LAST TOLERANCE 5%
J 0
(-8400 3150);
DISPLAY 0.489362 (-8400 3150);
PAINT SKYBLUE (-8400 3150);
FORCEPROP 1 LAST MATERIAL EMPTY
J 0
(-8300 3150);
DISPLAY 0.489362 (-8300 3150);
PAINT SKYBLUE (-8300 3150);
FORCEPROP 2 LAST CDS_LIB pure_quanta
J 0
(-8625 3150);
PAINT MONO (-8625 3150);
DISPLAY INVISIBLE (-8625 3150);
FORCEPROP 1 LAST WATTAGE 1/16W
J 2
(-8425 3225);
DISPLAY 0.510638 (-8425 3225);
PAINT SKYBLUE (-8425 3225);
DISPLAY INVISIBLE (-8425 3225);
FORCEPROP 1 LAST PACK_TYPE 0402LF
J 0
(-8725 3225);
DISPLAY 0.510638 (-8725 3225);
PAINT SKYBLUE (-8725 3225);
DISPLAY INVISIBLE (-8725 3225);
FORCEPROP 1 LAST PATH I99
J 0
(-8675 3300);
DISPLAY 0.978723 (-8675 3300);
PAINT WHITE (-8675 3300);
DISPLAY INVISIBLE (-8675 3300);
FORCEPROP 1 LAST PART_NUMBER CS31002JB08
J 0
(-8725 3200);
DISPLAY 0.510638 (-8725 3200);
PAINT SKYBLUE (-8725 3200);
DISPLAY INVISIBLE (-8725 3200);
FORCEADD DNS..2
(-8600 3975);
PAINT RED (-8600 3975);
FORCEPROP 2 LAST CDS_LIB mstr_misc
J 0
(-8600 3975);
PAINT MONO (-8600 3975);
DISPLAY INVISIBLE (-8600 3975);
FORCEPROP 1 LAST COMMENT_BODY TRUE
R 1
J 0
(-8525 3750);
DISPLAY 0.872340 (-8525 3750);
PAINT GREEN (-8525 3750);
DISPLAY INVISIBLE (-8525 3750);
FORCEADD DNS..2
(-8600 3125);
PAINT RED (-8600 3125);
FORCEPROP 2 LAST CDS_LIB mstr_misc
J 0
(-8600 3125);
DISPLAY INVISIBLE (-8600 3125);
FORCEPROP 1 LAST COMMENT_BODY TRUE
R 1
J 0
(-8525 2900);
DISPLAY 0.872340 (-8525 2900);
PAINT GREEN (-8525 2900);
DISPLAY INVISIBLE (-8525 2900);
FORCEADD DNS..2
(-8600 4925);
PAINT RED (-8600 4925);
FORCEPROP 2 LAST CDS_LIB mstr_misc
J 0
(-8600 4925);
PAINT MONO (-8600 4925);
DISPLAY INVISIBLE (-8600 4925);
FORCEPROP 1 LAST COMMENT_BODY TRUE
R 1
J 0
(-8525 4700);
DISPLAY 0.872340 (-8525 4700);
PAINT GREEN (-8525 4700);
DISPLAY INVISIBLE (-8525 4700);
FORCEADD DNS..2
(-8600 4800);
PAINT RED (-8600 4800);
FORCEPROP 2 LAST CDS_LIB mstr_misc
J 0
(-8600 4800);
PAINT MONO (-8600 4800);
DISPLAY INVISIBLE (-8600 4800);
FORCEPROP 1 LAST COMMENT_BODY TRUE
R 1
J 0
(-8525 4575);
DISPLAY 0.872340 (-8525 4575);
PAINT GREEN (-8525 4575);
DISPLAY INVISIBLE (-8525 4575);
FORCEADD DNS..2
(-8650 5475);
PAINT RED (-8650 5475);
FORCEPROP 2 LAST CDS_LIB mstr_misc
J 0
(-8650 5475);
PAINT MONO (-8650 5475);
DISPLAY INVISIBLE (-8650 5475);
FORCEPROP 1 LAST COMMENT_BODY TRUE
R 1
J 0
(-8575 5250);
DISPLAY 0.872340 (-8575 5250);
PAINT GREEN (-8575 5250);
DISPLAY INVISIBLE (-8575 5250);
FORCEADD DNS..2
(-8600 4550);
PAINT RED (-8600 4550);
FORCEPROP 2 LAST CDS_LIB mstr_misc
J 0
(-8600 4550);
DISPLAY INVISIBLE (-8600 4550);
FORCEPROP 1 LAST COMMENT_BODY TRUE
R 1
J 0
(-8525 4325);
DISPLAY 0.872340 (-8525 4325);
PAINT GREEN (-8525 4325);
DISPLAY INVISIBLE (-8525 4325);
FORCEADD DNS..2
(-3950 5275);
PAINT RED (-3950 5275);
FORCEPROP 2 LAST CDS_LIB mstr_misc
J 0
(-3950 5275);
DISPLAY INVISIBLE (-3950 5275);
FORCEPROP 1 LAST COMMENT_BODY TRUE
R 1
J 0
(-3875 5050);
DISPLAY 0.872340 (-3875 5050);
PAINT GREEN (-3875 5050);
DISPLAY INVISIBLE (-3875 5050);
FORCEADD QUANTA_TITLE_BLOCK_C..1
(0 0);
FORCEPROP 0 LAST CDS_CON_LAST_MODIFIED Thu Sep 14 16:12:04 2023
J 0
(-1885 15);
DISPLAY INVISIBLE (-1885 15);
FORCEPROP 1 LAST CUSTOM_TXT_CDS <CON_LAST_MODIFIED>
J 0
(-1885 15);
DISPLAY 0.978723 (-1885 15);
FORCEPROP 2 LAST CUSTOM_TXT_CDS <XR_PAGE_TITLE>
J 0
(-7890 5250);
DISPLAY 0.638298 (-7890 5250);
PAINT PINK (-7890 5250);
DISPLAY INVISIBLE (-7890 5250);
FORCEPROP 1 LAST CUSTOM_TXT_CDS <NAME_2>
J 0
(-3175 50);
FORCEPROP 1 LAST CUSTOM_TXT_CDS <NAME_1>
J 0
(-3175 175);
FORCEPROP 1 LAST CUSTOM_TXT_CDS <Q_NUMBER>
J 0
(-1403 103);
DISPLAY 1.212766 (-1403 103);
FORCEPROP 1 LAST CUSTOM_TXT_CDS <Q_PROJ>
J 0
(-2382 102);
DISPLAY 1.212766 (-2382 102);
FORCEPROP 1 LAST CUSTOM_TXT_CDS <Q_REV>
J 0
(-184 103);
DISPLAY 1.212766 (-184 103);
FORCEPROP 1 LAST CUSTOM_TXT_CDS <CON_PAGE_NUM> OF <CON_TOTAL_PAGES>
J 0
(-446 18);
DISPLAY 0.978723 (-446 18);
FORCEPROP 1 LAST Q_TITLE CPU HW STRAP PIN
J 0
(-9300 75);
DISPLAY 2.446809 (-9300 75);
PAINT GREEN (-9300 75);
FORCEPROP 2 LAST PAGE_BORDER TRUE
J 0
(-7890 5250);
DISPLAY 0.638298 (-7890 5250);
PAINT PINK (-7890 5250);
DISPLAY INVISIBLE (-7890 5250);
FORCEPROP 2 LAST CDS_LIB pure_quanta
J 0
(0 0);
DISPLAY INVISIBLE (0 0);
FORCEPROP 1 LAST CDS_LMAN_SYM_OUTLINE -9475,6775,100,-125
J 0
(0 0);
DISPLAY 0.468085 (0 0);
PAINT GREEN (0 0);
DISPLAY INVISIBLE (0 0);
FORCEPROP 2 LAST CDS_XR_PAGE_TITLE CR-76 : @T6G_MB_LIB.T6G(SCH_1):PAGE76
J 0
(-7890 5250);
DISPLAY 0.638298 (-7890 5250);
PAINT PINK (-7890 5250);
DISPLAY INVISIBLE (-7890 5250);
FORCEPROP 1 LAST Q_DEPT BU9
J 1
(-3763 49);
DISPLAY 1.957447 (-3763 49);
PAINT GREEN (-3763 49);
DISPLAY INVISIBLE (-3763 49);
FORCEPROP 1 LAST COMMENT_BODY TRUE
J 0
(12 -13);
DISPLAY 0.978723 (12 -13);
PAINT GREEN (12 -13);
DISPLAY INVISIBLE (12 -13);
FORCEADD DNS..2
(-3925 5000);
PAINT RED (-3925 5000);
FORCEPROP 2 LAST CDS_LIB mstr_misc
J 0
(-3925 5000);
PAINT MONO (-3925 5000);
DISPLAY INVISIBLE (-3925 5000);
FORCEPROP 1 LAST COMMENT_BODY TRUE
R 1
J 0
(-3850 4775);
DISPLAY 0.872340 (-3850 4775);
PAINT GREEN (-3850 4775);
DISPLAY INVISIBLE (-3850 4775);
FORCEADD DNS..2
(-3900 4650);
PAINT RED (-3900 4650);
FORCEPROP 2 LAST CDS_LIB mstr_misc
J 0
(-3900 4650);
DISPLAY INVISIBLE (-3900 4650);
FORCEPROP 1 LAST COMMENT_BODY TRUE
R 1
J 0
(-3825 4425);
DISPLAY 0.872340 (-3825 4425);
PAINT GREEN (-3825 4425);
DISPLAY INVISIBLE (-3825 4425);
WIRE 16 273 (-8950 2525)(-7925 2525);
WIRE 16 273 (-8950 2325)(-8950 2525);
WIRE 16 273 (-7475 2525)(-7925 2525);
WIRE 16 273 (-7925 2325)(-7925 2525);
WIRE 16 273 (-8950 2325)(-7925 2325);
WIRE 16 273 (-7925 2325)(-7475 2325);
WIRE 16 273 (-7925 2050)(-7925 2325);
WIRE 16 273 (-6275 2525)(-7475 2525);
WIRE 16 273 (-7475 2325)(-7475 2525);
WIRE 16 273 (-8950 2325)(-8950 2050);
WIRE 16 273 (-8950 2050)(-7925 2050);
WIRE 16 273 (-8950 2050)(-8950 1675);
WIRE 16 273 (-7475 2325)(-6275 2325);
WIRE 16 273 (-7475 2325)(-7475 2050);
WIRE 16 273 (-5800 2525)(-6275 2525);
WIRE 16 273 (-6275 2325)(-6275 2525);
WIRE 16 273 (-7925 2050)(-7475 2050);
WIRE 16 273 (-7925 1675)(-7925 2050);
WIRE 16 273 (-8950 1675)(-7925 1675);
WIRE 16 273 (-7925 1675)(-7475 1675);
WIRE 16 273 (-7925 1400)(-7925 1675);
WIRE 16 273 (-6275 2050)(-7475 2050);
WIRE 16 273 (-7475 2050)(-7475 1675);
WIRE 16 273 (-6275 2325)(-5800 2325);
WIRE 16 273 (-6275 2050)(-6275 2325);
WIRE 16 273 (-5800 2525)(-4625 2525);
WIRE 16 273 (-5800 2525)(-5800 2325);
WIRE 16 273 (-8950 1675)(-8950 1400);
WIRE 16 273 (-8950 1400)(-7925 1400);
WIRE 16 273 (-8950 1125)(-8950 1400);
WIRE 16 273 (-4625 2325)(-5800 2325);
WIRE 16 273 (-5800 2050)(-5800 2325);
WIRE 16 273 (-4150 2525)(-4625 2525);
WIRE 16 273 (-4625 2325)(-4625 2525);
WIRE 16 273 (-5800 2050)(-6275 2050);
WIRE 16 273 (-6275 1675)(-6275 2050);
WIRE 16 273 (-6275 1675)(-7475 1675);
WIRE 16 273 (-7475 1675)(-7475 1400);
WIRE 16 273 (-7925 1400)(-7475 1400);
WIRE 16 273 (-7925 1125)(-7925 1400);
WIRE 16 273 (-8950 1125)(-7925 1125);
WIRE 16 273 (-7925 1125)(-7475 1125);
WIRE 16 273 (-7925 1125)(-7925 825);
WIRE 16 273 (-6275 1400)(-7475 1400);
WIRE 16 273 (-7475 1125)(-7475 1400);
WIRE 16 273 (-5800 1675)(-6275 1675);
WIRE 16 273 (-6275 1400)(-6275 1675);
WIRE 16 273 (-4625 2050)(-5800 2050);
WIRE 16 273 (-5800 1675)(-5800 2050);
WIRE 16 273 (-4625 2325)(-4150 2325);
WIRE 16 273 (-4625 2325)(-4625 2050);
WIRE 16 273 (-2175 2525)(-4150 2525);
WIRE 16 273 (-4150 2525)(-4150 2325);
WIRE 16 273 (-8950 1125)(-8950 825);
WIRE 16 273 (-8950 825)(-7925 825);
WIRE 16 273 (-4150 2325)(-2175 2325);
WIRE 16 273 (-4150 2050)(-4150 2325);
WIRE 16 273 (-2175 2325)(-2175 2525);
WIRE 16 2730 (-5800 1675)(-4625 2050);
WIRE 16 273 (-4625 2050)(-4150 2050);
WIRE 16 273 (-4625 1675)(-4625 2050);
WIRE 16 273 (-4625 1675)(-5800 1675);
WIRE 16 273 (-5800 1400)(-5800 1675);
WIRE 16 273 (-5800 1400)(-6275 1400);
WIRE 16 273 (-6275 1125)(-6275 1400);
WIRE 16 273 (-6275 1125)(-7475 1125);
WIRE 16 273 (-7475 1125)(-7475 825);
WIRE 16 273 (-7925 825)(-7475 825);
WIRE 16 273 (-6275 825)(-7475 825);
WIRE 16 273 (-5800 1125)(-6275 1125);
WIRE 16 273 (-6275 1125)(-6275 825);
WIRE 16 2730 (-5800 1400)(-4625 1675);
WIRE 16 273 (-5800 1400)(-4625 1400);
WIRE 16 273 (-5800 1125)(-5800 1400);
WIRE 16 2730 (-4625 1675)(-4150 2050);
WIRE 16 273 (-4625 1675)(-4150 1675);
WIRE 16 273 (-4625 1400)(-4625 1675);
WIRE 16 273 (-4150 2050)(-2175 2050);
WIRE 16 273 (-4150 1675)(-4150 2050);
WIRE 16 273 (-2175 2050)(-2175 2325);
WIRE 16 273 (-2175 1675)(-2175 2050);
WIRE 16 2730 (-4625 1400)(-4150 1675);
WIRE 16 273 (-4150 1675)(-2175 1675);
WIRE 16 273 (-4150 1675)(-4150 1400);
WIRE 16 273 (-4625 1400)(-4150 1400);
WIRE 16 273 (-4625 1400)(-4625 1125);
WIRE 16 273 (-5800 1125)(-4625 1125);
WIRE 16 273 (-5800 825)(-5800 1125);
WIRE 16 273 (-5800 825)(-6275 825);
WIRE 16 273 (-4625 825)(-5800 825);
WIRE 16 273 (-4625 1125)(-4150 1125);
WIRE 16 273 (-4625 1125)(-4625 825);
WIRE 16 273 (-4150 1400)(-2175 1400);
WIRE 16 273 (-4150 1400)(-4150 1125);
WIRE 16 273 (-2175 1400)(-2175 1675);
WIRE 16 273 (-2175 1125)(-2175 1400);
WIRE 16 273 (-4150 1125)(-2175 1125);
WIRE 16 273 (-4150 825)(-4150 1125);
WIRE 16 273 (-4625 825)(-4150 825);
WIRE 16 273 (-2175 825)(-4150 825);
WIRE 16 273 (-2175 825)(-2175 1125);
WIRE 16 -1 (-3850 4375)(-2575 4375);
FORCEPROP 2 LAST SIG_NAME PD_ESPI_CPU1_CLK2
J 0
(-3410 4385);
DISPLAY 0.489362 (-3410 4385);
WIRE 16 -1 (-3825 4650)(-2575 4650);
FORCEPROP 2 LAST SIG_NAME SPI_CPU1_CLK
J 0
(-3385 4660);
DISPLAY 0.489362 (-3385 4660);
WIRE 16 -1 (-3850 5000)(-2575 5000);
FORCEPROP 2 LAST SIG_NAME CLK_CPU1_RTCCLK
J 0
(-3410 5010);
DISPLAY 0.489362 (-3410 5010);
WIRE 16 -1 (-3875 5275)(-2575 5275);
FORCEPROP 2 LAST SIG_NAME PD_ESPI_CPU1_CLK2
J 0
(-3385 5285);
DISPLAY 0.489362 (-3385 5285);
WIRE 16 -1 (-8950 3350)(-8950 3600);
WIRE 16 -1 (-8950 3350)(-8750 3350);
WIRE 16 -1 (-8950 3350)(-8950 3150);
WIRE 16 -1 (-8950 3600)(-8750 3600);
WIRE 16 -1 (-8950 3725)(-8950 3600);
WIRE 16 -1 (-8950 3725)(-8950 3975);
WIRE 16 -1 (-8950 3725)(-8750 3725);
WIRE 16 -1 (-8950 3150)(-8725 3150);
WIRE 16 -1 (-8950 3150)(-8950 2900);
WIRE 16 -1 (-8950 3975)(-8950 4250);
WIRE 16 -1 (-8950 3975)(-8750 3975);
WIRE 16 -1 (-8950 4250)(-8750 4250);
WIRE 16 -1 (-8950 5450)(-8950 5725);
WIRE 16 -1 (-8950 5450)(-8750 5450);
WIRE 16 -1 (-8950 5450)(-8950 5175);
WIRE 16 -1 (-8950 5725)(-8950 5900);
WIRE 16 -1 (-8950 5725)(-8725 5725);
WIRE 16 -1 (-8950 5175)(-8725 5175);
WIRE 16 -1 (-8950 5175)(-8950 4925);
WIRE 16 -1 (-8950 4925)(-8725 4925);
WIRE 16 -1 (-8950 4800)(-8950 4925);
WIRE 16 -1 (-8950 4800)(-8725 4800);
WIRE 16 -1 (-8950 4800)(-8950 4550);
WIRE 16 -1 (-8950 4550)(-8725 4550);
WIRE 16 -1 (-4050 5550)(-4275 5550);
WIRE 16 -1 (-4275 5750)(-4275 5550);
WIRE 16 -1 (-4275 5275)(-4275 5550);
WIRE 16 -1 (-4275 5275)(-4075 5275);
WIRE 16 -1 (-4275 5275)(-4275 5000);
WIRE 16 -1 (-4275 5000)(-4050 5000);
WIRE 16 -1 (-4275 4375)(-4050 4375);
WIRE 16 -1 (-4275 4375)(-4275 4650);
WIRE 16 -1 (-4275 4375)(-4275 4100);
WIRE 16 -1 (-4275 4100)(-4050 4100);
WIRE 16 -1 (-4275 4100)(-4275 3775);
WIRE 16 -1 (-4275 4650)(-4025 4650);
WIRE 16 -1 (-2575 4100)(-3850 4100);
FORCEPROP 2 LAST SIG_NAME CLK_CPU1_RTCCLK
J 0
(-3385 4110);
DISPLAY 0.489362 (-3385 4110);
WIRE 16 -1 (-8550 3975)(-7275 3975);
FORCEPROP 2 LAST SIG_NAME CPU0_ROM_TYPE_SELECT
J 0
(-8110 3985);
DISPLAY 0.489362 (-8110 3985);
WIRE 16 -1 (-8525 4925)(-7275 4925);
FORCEPROP 2 LAST SIG_NAME CLK_ESPI_CPU0_CLK1
J 0
(-8035 4935);
DISPLAY 0.489362 (-8035 4935);
WIRE 16 -1 (-8550 5450)(-7275 5450);
FORCEPROP 2 LAST SIG_NAME UART_CPU0_SCM_UART1_TX
J 0
(-8060 5460);
DISPLAY 0.489362 (-8060 5460);
WIRE 16 -1 (-8525 4800)(-7275 4800);
FORCEPROP 2 LAST SIG_NAME CLK_CPU0_RTCCLK
J 0
(-8035 4810);
DISPLAY 0.489362 (-8035 4810);
WIRE 16 -1 (-8525 3150)(-7275 3150);
FORCEPROP 2 LAST SIG_NAME SPI_CPU0_CLK
J 0
(-8035 3160);
DISPLAY 0.489362 (-8035 3160);
WIRE 16 -1 (-7275 3600)(-8550 3600);
FORCEPROP 2 LAST SIG_NAME CLK_CPU0_RTCCLK
J 0
(-8110 3610);
DISPLAY 0.489362 (-8110 3610);
WIRE 16 -1 (-8525 5175)(-7275 5175);
FORCEPROP 2 LAST SIG_NAME CPU0_ROM_TYPE_SELECT
J 0
(-8035 5185);
DISPLAY 0.489362 (-8035 5185);
WIRE 16 -1 (-8550 3350)(-7275 3350);
FORCEPROP 2 LAST SIG_NAME PD_ESPI_CPU0_CLK2
J 0
(-8110 3360);
DISPLAY 0.489362 (-8110 3360);
WIRE 16 -1 (-8525 5725)(-7275 5725);
FORCEPROP 2 LAST SIG_NAME SPI_CPU0_CLK
J 0
(-8035 5735);
DISPLAY 0.489362 (-8035 5735);
WIRE 16 -1 (-3850 5550)(-2575 5550);
FORCEPROP 2 LAST SIG_NAME SPI_CPU1_CLK
J 0
(-3360 5560);
DISPLAY 0.489362 (-3360 5560);
WIRE 16 -1 (-7275 3725)(-8550 3725);
FORCEPROP 2 LAST SIG_NAME CLK_ESPI_CPU0_CLK1
J 0
(-8110 3735);
DISPLAY 0.489362 (-8110 3735);
WIRE 16 -1 (-8525 4550)(-7275 4550);
FORCEPROP 2 LAST SIG_NAME PD_ESPI_CPU0_CLK2
J 0
(-8035 4560);
DISPLAY 0.489362 (-8035 4560);
WIRE 16 -1 (-8550 4250)(-7275 4250);
FORCEPROP 2 LAST SIG_NAME UART_CPU0_SCM_UART1_TX
J 0
(-8110 4260);
DISPLAY 0.489362 (-8110 4260);
DOT 1 (-8950 3725);
DOT 1 (-8950 3350);
DOT 1 (-8950 3150);
DOT 1 (-4275 4375);
DOT 1 (-8950 5450);
DOT 1 (-8950 4925);
DOT 1 (-8950 4800);
DOT 1 (-8950 5175);
DOT 1 (-8950 3975);
DOT 1 (-8950 3600);
DOT 1 (-4275 5275);
DOT 1 (-2175 2325);
DOT 1 (-2175 1675);
DOT 1 (-2175 2050);
DOT 1 (-2175 1400);
DOT 1 (-2175 1125);
DOT 1 (-4150 2525);
DOT 1 (-4150 2325);
DOT 1 (-4625 2325);
DOT 1 (-5800 2525);
DOT 1 (-5800 2325);
DOT 1 (-4150 1675);
DOT 1 (-4150 2050);
DOT 1 (-4150 1125);
DOT 1 (-4625 1400);
DOT 1 (-4625 1125);
DOT 1 (-4150 825);
DOT 1 (-4625 825);
DOT 1 (-5800 2050);
DOT 1 (-5800 1675);
DOT 1 (-5800 1400);
DOT 1 (-5800 1125);
DOT 1 (-5800 825);
DOT 1 (-6275 2525);
DOT 1 (-6275 2325);
DOT 1 (-7475 2525);
DOT 1 (-7925 2525);
DOT 1 (-7925 2325);
DOT 1 (-6275 1675);
DOT 1 (-6275 2050);
DOT 1 (-6275 1125);
DOT 1 (-6275 1400);
DOT 1 (-6275 825);
DOT 1 (-7475 2050);
DOT 1 (-7475 1675);
DOT 1 (-7475 1400);
DOT 1 (-7475 1125);
DOT 1 (-7925 2050);
DOT 1 (-7925 1675);
DOT 1 (-7925 1400);
DOT 1 (-7925 1125);
DOT 1 (-7475 825);
DOT 1 (-7925 825);
DOT 1 (-8950 2050);
DOT 1 (-8950 1675);
DOT 1 (-8950 1125);
DOT 1 (-8950 1400);
DOT 1 (-4625 2525);
DOT 1 (-4625 2050);
DOT 1 (-4150 1400);
DOT 1 (-4625 1675);
DOT 1 (-8950 2325);
DOT 1 (-4275 4100);
DOT 1 (-4275 5550);
DOT 1 (-8950 5725);
DOT 1 (-7475 2325);
FORCENOTE
CPU1
(-4525 2425) 0;
DISPLAY LEFT (-4525 2425);
DISPLAY 1.021277 (-4525 2425);
PAINT WHITE (-4525 2425);
FORCENOTE
CLK_CPU0_RTCCLK
(-7400 1225) 0;
DISPLAY LEFT (-7400 1225);
DISPLAY 1.021277 (-7400 1225);
PAINT WHITE (-7400 1225);
FORCENOTE
CLK_ESPI_CPU0_CLK1
(-7400 1500) 0;
DISPLAY LEFT (-7400 1500);
DISPLAY 1.021277 (-7400 1500);
PAINT WHITE (-7400 1500);
FORCENOTE
0
(-4425 925) 0;
DISPLAY LEFT (-4425 925);
DISPLAY 1.021277 (-4425 925);
PAINT WHITE (-4425 925);
FORCENOTE
RSVD
(-4100 950) 0;
DISPLAY LEFT (-4100 950);
DISPLAY 1.021277 (-4100 950);
PAINT WHITE (-4100 950);
FORCENOTE
PD_ESPI_CPU0_CLK2
(-7400 925) 0;
DISPLAY LEFT (-7400 925);
DISPLAY 1.021277 (-7400 925);
PAINT WHITE (-7400 925);
FORCENOTE
INTERNAL
(-7875 2450) 0;
DISPLAY LEFT (-7875 2450);
DISPLAY 1.021277 (-7875 2450);
PAINT WHITE (-7875 2450);
FORCENOTE
CPU0 STRAP
(-9050 6150) 0;
DISPLAY LEFT (-9050 6150);
DISPLAY 3.297872 (-9050 6150);
PAINT WHITE (-9050 6150);
FORCENOTE
ESPI_CLK0
(-8850 2175) 0;
DISPLAY LEFT (-8850 2175);
DISPLAY 1.021277 (-8850 2175);
PAINT WHITE (-8850 2175);
FORCENOTE
50K PU
(-7850 1800) 0;
DISPLAY LEFT (-7850 1800);
DISPLAY 1.021277 (-7850 1800);
PAINT WHITE (-7850 1800);
FORCENOTE
50K PD
(-7850 1500) 0;
DISPLAY LEFT (-7850 1500);
DISPLAY 1.021277 (-7850 1500);
PAINT WHITE (-7850 1500);
FORCENOTE
CPU1 STRAP
(-4400 6075) 0;
DISPLAY LEFT (-4400 6075);
DISPLAY 3.297872 (-4400 6075);
PAINT WHITE (-4400 6075);
FORCENOTE
1
(-6050 2175) 0;
DISPLAY LEFT (-6050 2175);
DISPLAY 1.021277 (-6050 2175);
PAINT WHITE (-6050 2175);
FORCENOTE
50K PU
(-7850 1925) 0;
DISPLAY LEFT (-7850 1925);
DISPLAY 1.021277 (-7850 1925);
PAINT WHITE (-7850 1925);
FORCENOTE
PD
(-7850 1225) 0;
DISPLAY LEFT (-7850 1225);
DISPLAY 1.021277 (-7850 1225);
PAINT WHITE (-7850 1225);
FORCENOTE
PD
(-7850 925) 0;
DISPLAY LEFT (-7850 925);
DISPLAY 1.021277 (-7850 925);
PAINT WHITE (-7850 925);
FORCENOTE
0
(-6025 925) 0;
DISPLAY LEFT (-6025 925);
DISPLAY 1.021277 (-6025 925);
PAINT WHITE (-6025 925);
FORCENOTE
1X: ESPI
(-4100 1725) 0;
DISPLAY LEFT (-4100 1725);
DISPLAY 1.021277 (-4100 1725);
PAINT WHITE (-4100 1725);
FORCENOTE
SPI_CPU1_CLK
(-5750 2175) 0;
DISPLAY LEFT (-5750 2175);
DISPLAY 1.021277 (-5750 2175);
PAINT WHITE (-5750 2175);
FORCENOTE
(DEFAULT)
(-4600 2350) 0;
DISPLAY LEFT (-4600 2350);
DISPLAY 1.021277 (-4600 2350);
PAINT WHITE (-4600 2350);
FORCENOTE
1
(-4425 2175) 0;
DISPLAY LEFT (-4425 2175);
DISPLAY 1.021277 (-4425 2175);
PAINT WHITE (-4425 2175);
FORCENOTE
DESCRIPTION
(-3450 2400) 0;
DISPLAY LEFT (-3450 2400);
DISPLAY 1.021277 (-3450 2400);
PAINT WHITE (-3450 2400);
FORCENOTE
0
(-6025 1225) 0;
DISPLAY LEFT (-6025 1225);
DISPLAY 1.021277 (-6025 1225);
PAINT WHITE (-6025 1225);
FORCENOTE
CPUX PIN NAME
(-8850 2375) 0;
DISPLAY LEFT (-8850 2375);
DISPLAY 1.021277 (-8850 2375);
PAINT WHITE (-8850 2375);
FORCENOTE
UART1_TXD||AGPIO142
(-8850 1875) 0;
DISPLAY LEFT (-8850 1875);
DISPLAY 1.021277 (-8850 1875);
PAINT WHITE (-8850 1875);
FORCENOTE
AGPIO109
(-8850 1725) 0;
DISPLAY LEFT (-8850 1725);
DISPLAY 1.021277 (-8850 1725);
PAINT WHITE (-8850 1725);
FORCENOTE
50K PD
(-7850 2175) 0;
DISPLAY LEFT (-7850 2175);
DISPLAY 1.021277 (-7850 2175);
PAINT WHITE (-7850 2175);
FORCENOTE
ESPI_CLK1
(-8850 1500) 0;
DISPLAY LEFT (-8850 1500);
DISPLAY 1.021277 (-8850 1500);
PAINT WHITE (-8850 1500);
FORCENOTE
ESPI_CLK2||AGPIO74
(-8850 925) 0;
DISPLAY LEFT (-8850 925);
DISPLAY 1.021277 (-8850 925);
PAINT WHITE (-8850 925);
FORCENOTE
CPU0
(-6150 2425) 0;
DISPLAY LEFT (-6150 2425);
DISPLAY 1.021277 (-6150 2425);
PAINT WHITE (-6150 2425);
FORCENOTE
(DEFAULT)
(-6225 2350) 0;
DISPLAY LEFT (-6225 2350);
DISPLAY 1.021277 (-6225 2350);
PAINT WHITE (-6225 2350);
FORCENOTE
PU/PD
(-7875 2375) 0;
DISPLAY LEFT (-7875 2375);
DISPLAY 1.021277 (-7875 2375);
PAINT WHITE (-7875 2375);
FORCENOTE
CPU0 NET NAME
(-7400 2400) 0;
DISPLAY LEFT (-7400 2400);
DISPLAY 1.021277 (-7400 2400);
PAINT WHITE (-7400 2400);
FORCENOTE
1
(-6050 1775) 0;
DISPLAY LEFT (-6050 1775);
DISPLAY 1.021277 (-6050 1775);
PAINT WHITE (-6050 1775);
FORCENOTE
RTCCLK
(-8850 1225) 0;
DISPLAY LEFT (-8850 1225);
DISPLAY 1.021277 (-8850 1225);
PAINT WHITE (-8850 1225);
FORCENOTE
0
(-6025 1500) 0;
DISPLAY LEFT (-6025 1500);
DISPLAY 1.021277 (-6025 1500);
PAINT WHITE (-6025 1500);
FORCENOTE
CPU0_ROM_TYPE_SELECT
(-7400 1775) 0;
DISPLAY LEFT (-7400 1775);
DISPLAY 1.021277 (-7400 1775);
PAINT WHITE (-7400 1775);
FORCENOTE
ROMTYPE
(-4100 1950) 0;
DISPLAY LEFT (-4100 1950);
DISPLAY 1.021277 (-4100 1950);
PAINT WHITE (-4100 1950);
FORCENOTE
00: RSVD
(-4100 1800) 0;
DISPLAY LEFT (-4100 1800);
DISPLAY 1.021277 (-4100 1800);
PAINT WHITE (-4100 1800);
FORCENOTE
0
(-4425 1225) 0;
DISPLAY LEFT (-4425 1225);
DISPLAY 1.021277 (-4425 1225);
PAINT WHITE (-4425 1225);
FORCENOTE
PD_ESPI_CPU1_CLK2
(-5750 925) 0;
DISPLAY LEFT (-5750 925);
DISPLAY 1.021277 (-5750 925);
PAINT WHITE (-5750 925);
FORCENOTE
0
(-6050 1900) 0;
DISPLAY LEFT (-6050 1900);
DISPLAY 1.021277 (-6050 1900);
PAINT WHITE (-6050 1900);
FORCENOTE
SPI_CPU0_CLK
(-7400 2175) 0;
DISPLAY LEFT (-7400 2175);
DISPLAY 1.021277 (-7400 2175);
PAINT WHITE (-7400 2175);
FORCENOTE
CPU1 NET NAME
(-5750 2375) 0;
DISPLAY LEFT (-5750 2375);
DISPLAY 1.021277 (-5750 2375);
PAINT WHITE (-5750 2375);
FORCENOTE
CLKGEN SELECTION
(-4100 2225) 0;
DISPLAY LEFT (-4100 2225);
DISPLAY 1.021277 (-4100 2225);
PAINT WHITE (-4100 2225);
FORCENOTE
0: EXTERNAL CLKGEN MODE
(-4100 2150) 0;
DISPLAY LEFT (-4100 2150);
DISPLAY 1.021277 (-4100 2150);
PAINT WHITE (-4100 2150);
FORCENOTE
1: INTERNAL CLKGEN MODE
(-4100 2075) 0;
DISPLAY LEFT (-4100 2075);
DISPLAY 1.021277 (-4100 2075);
PAINT WHITE (-4100 2075);
FORCENOTE
01: SPI ROM(DEFAULT)
(-4100 1875) 0;
DISPLAY LEFT (-4100 1875);
DISPLAY 1.021277 (-4100 1875);
PAINT WHITE (-4100 1875);
FORCENOTE
ALTERNATE IMAGE
(-4100 1575) 0;
DISPLAY LEFT (-4100 1575);
DISPLAY 1.021277 (-4100 1575);
PAINT WHITE (-4100 1575);
FORCENOTE
0: BOTTOM HALF 64MB ROM
(-4075 1500) 0;
DISPLAY LEFT (-4075 1500);
DISPLAY 1.021277 (-4075 1500);
PAINT WHITE (-4075 1500);
FORCENOTE
1: TOP HALF 64MB ROM
(-4075 1425) 0;
DISPLAY LEFT (-4075 1425);
DISPLAY 1.021277 (-4075 1425);
PAINT WHITE (-4075 1425);
FORCENOTE
1: RTCCLK IS INPUT & USED AS BYPASS CLK
(-4100 1175) 0;
DISPLAY LEFT (-4100 1175);
DISPLAY 1.021277 (-4100 1175);
PAINT WHITE (-4100 1175);
FORCENOTE
BYPASS RTC
(-4100 1325) 0;
DISPLAY LEFT (-4100 1325);
DISPLAY 1.021277 (-4100 1325);
PAINT WHITE (-4100 1325);
FORCENOTE
0: NORMAL MODE, 32KHZ XTAL AS SOURCE
(-4100 1250) 0;
DISPLAY LEFT (-4100 1250);
DISPLAY 1.021277 (-4100 1250);
PAINT WHITE (-4100 1250);
FORCENOTE
CLK_CPU1_RTCCLK
(-5750 1225) 0;
DISPLAY LEFT (-5750 1225);
DISPLAY 1.021277 (-5750 1225);
PAINT WHITE (-5750 1225);
FORCENOTE
UART_CPU0_SCM_UART1_TX
(-7400 1900) 0;
DISPLAY LEFT (-7400 1900);
DISPLAY 1.021277 (-7400 1900);
PAINT WHITE (-7400 1900);
QUIT
